FILE_TYPE = MACRO_DRAWING;
SET COLOR_WIRE YELLOW;
SET COLOR_PROP ORANGE;
SET COLOR_DOT WHITE;
SET COLOR_ARC YELLOW;
SET COLOR_BODY GREEN;
SET COLOR_NOTE PURPLE;
SET PROP_DISPLAY VALUE;
SET PAGE_NUMBER P97;
FORCEADD OFFPAGE..5
(-8050 2025);
FORCEPROP 2 LAST $XR0 37 
J 0
(-8304 2025);
DISPLAY 0.638298 (-8304 2025);
PAINT MONO (-8304 2025);
FORCEPROP 2 LAST CDS_LIB mstr_standard
J 0
(-8050 2025);
DISPLAY 0.808511 (-8050 2025);
DISPLAY INVISIBLE (-8050 2025);
FORCEPROP 1 LAST OFFPAGE TRUE
J 0
(-7725 1900);
DISPLAY 0.872340 (-7725 1900);
PAINT GREEN (-7725 1900);
DISPLAY INVISIBLE (-7725 1900);
FORCEPROP 1 LAST COMMENT_BODY TRUE
J 0
(-7950 1950);
DISPLAY 0.872340 (-7950 1950);
PAINT GREEN (-7950 1950);
DISPLAY INVISIBLE (-7950 1950);
FORCEPROP 2 LAST PATH I1
J 0
(-8250 2075);
DISPLAY 1.021277 (-8250 2075);
DISPLAY INVISIBLE (-8250 2075);
FORCEADD OFFPAGE..6
(-8050 3675);
FORCEPROP 2 LAST $XR0 37 
J 0
(-8329 3675);
DISPLAY 0.638298 (-8329 3675);
PAINT MONO (-8329 3675);
FORCEPROP 2 LAST CDS_LIB mstr_standard
J 0
(-8050 3675);
DISPLAY 0.723404 (-8050 3675);
PAINT MONO (-8050 3675);
DISPLAY INVISIBLE (-8050 3675);
FORCEPROP 1 LAST OFFPAGE TRUE
J 0
(-7725 3550);
DISPLAY 0.872340 (-7725 3550);
PAINT GREEN (-7725 3550);
DISPLAY INVISIBLE (-7725 3550);
FORCEPROP 1 LAST COMMENT_BODY TRUE
J 0
(-7950 3600);
DISPLAY 0.872340 (-7950 3600);
PAINT GREEN (-7950 3600);
DISPLAY INVISIBLE (-7950 3600);
FORCEPROP 2 LAST PATH I10
J 0
(-8325 3725);
DISPLAY 1.021277 (-8325 3725);
DISPLAY INVISIBLE (-8325 3725);
FORCEADD TAP..1
(-5750 4175);
FORCEPROP 3 LASTPIN (-5800 4175) SIG_NAME M_A_CPU1_SA_DQ<5>
J 0
(-5790 4185);
DISPLAY 0.659574 (-5790 4185);
PAINT MONO (-5790 4185);
DISPLAY INVISIBLE (-5790 4185);
FORCEPROP 1 LASTPIN (-5800 4175) BN 5
J 0
(-5812 4183);
DISPLAY 0.489362 (-5812 4183);
PAINT GREEN (-5812 4183);
FORCEPROP 2 LAST CDS_LIB mstr_standard
J 0
(-5750 4175);
DISPLAY 0.723404 (-5750 4175);
PAINT MONO (-5750 4175);
DISPLAY INVISIBLE (-5750 4175);
FORCEPROP 1 LAST BODY_TYPE PLUMBING
J 0
(-5750 4225);
DISPLAY 0.872340 (-5750 4225);
PAINT GREEN (-5750 4225);
DISPLAY INVISIBLE (-5750 4225);
FORCEPROP 1 LAST HDL_TAP TRUE
J 0
(-5425 4050);
DISPLAY 0.872340 (-5425 4050);
DISPLAY INVISIBLE (-5425 4050);
FORCEPROP 1 LAST PATH I100
J 0
(-5752 4175);
DISPLAY 0.872340 (-5752 4175);
PAINT GREEN (-5752 4175);
DISPLAY INVISIBLE (-5752 4175);
FORCEADD TAP..1
(-5750 4325);
FORCEPROP 3 LASTPIN (-5800 4325) SIG_NAME M_A_CPU1_SA_DQ<8>
J 0
(-5790 4335);
DISPLAY 0.659574 (-5790 4335);
PAINT MONO (-5790 4335);
DISPLAY INVISIBLE (-5790 4335);
FORCEPROP 1 LASTPIN (-5800 4325) BN 8
J 0
(-5812 4333);
DISPLAY 0.489362 (-5812 4333);
PAINT GREEN (-5812 4333);
FORCEPROP 2 LAST CDS_LIB mstr_standard
J 0
(-5750 4325);
DISPLAY 0.723404 (-5750 4325);
PAINT MONO (-5750 4325);
DISPLAY INVISIBLE (-5750 4325);
FORCEPROP 1 LAST BODY_TYPE PLUMBING
J 0
(-5750 4375);
DISPLAY 0.872340 (-5750 4375);
PAINT GREEN (-5750 4375);
DISPLAY INVISIBLE (-5750 4375);
FORCEPROP 1 LAST HDL_TAP TRUE
J 0
(-5425 4200);
DISPLAY 0.872340 (-5425 4200);
DISPLAY INVISIBLE (-5425 4200);
FORCEPROP 1 LAST PATH I101
J 0
(-5752 4325);
DISPLAY 0.872340 (-5752 4325);
PAINT GREEN (-5752 4325);
DISPLAY INVISIBLE (-5752 4325);
FORCEADD TAP..1
(-5750 4375);
FORCEPROP 3 LASTPIN (-5800 4375) SIG_NAME M_A_CPU1_SA_DQ<9>
J 0
(-5790 4385);
DISPLAY 0.659574 (-5790 4385);
PAINT MONO (-5790 4385);
DISPLAY INVISIBLE (-5790 4385);
FORCEPROP 1 LASTPIN (-5800 4375) BN 9
J 0
(-5812 4383);
DISPLAY 0.489362 (-5812 4383);
PAINT GREEN (-5812 4383);
FORCEPROP 2 LAST CDS_LIB mstr_standard
J 0
(-5750 4375);
DISPLAY 0.723404 (-5750 4375);
PAINT MONO (-5750 4375);
DISPLAY INVISIBLE (-5750 4375);
FORCEPROP 1 LAST BODY_TYPE PLUMBING
J 0
(-5750 4425);
DISPLAY 0.872340 (-5750 4425);
PAINT GREEN (-5750 4425);
DISPLAY INVISIBLE (-5750 4425);
FORCEPROP 1 LAST HDL_TAP TRUE
J 0
(-5425 4250);
DISPLAY 0.872340 (-5425 4250);
DISPLAY INVISIBLE (-5425 4250);
FORCEPROP 1 LAST PATH I102
J 0
(-5752 4375);
DISPLAY 0.872340 (-5752 4375);
PAINT GREEN (-5752 4375);
DISPLAY INVISIBLE (-5752 4375);
FORCEADD TAP..1
(-5750 4275);
FORCEPROP 3 LASTPIN (-5800 4275) SIG_NAME M_A_CPU1_SA_DQ<7>
J 0
(-5790 4285);
DISPLAY 0.659574 (-5790 4285);
PAINT MONO (-5790 4285);
DISPLAY INVISIBLE (-5790 4285);
FORCEPROP 1 LASTPIN (-5800 4275) BN 7
J 0
(-5812 4283);
DISPLAY 0.489362 (-5812 4283);
PAINT GREEN (-5812 4283);
FORCEPROP 2 LAST CDS_LIB mstr_standard
J 0
(-5750 4275);
DISPLAY 0.723404 (-5750 4275);
PAINT MONO (-5750 4275);
DISPLAY INVISIBLE (-5750 4275);
FORCEPROP 1 LAST BODY_TYPE PLUMBING
J 0
(-5750 4325);
DISPLAY 0.872340 (-5750 4325);
PAINT GREEN (-5750 4325);
DISPLAY INVISIBLE (-5750 4325);
FORCEPROP 1 LAST HDL_TAP TRUE
J 0
(-5425 4150);
DISPLAY 0.872340 (-5425 4150);
DISPLAY INVISIBLE (-5425 4150);
FORCEPROP 1 LAST PATH I103
J 0
(-5752 4275);
DISPLAY 0.872340 (-5752 4275);
PAINT GREEN (-5752 4275);
DISPLAY INVISIBLE (-5752 4275);
FORCEADD TAP..1
(-5750 4525);
FORCEPROP 3 LASTPIN (-5800 4525) SIG_NAME M_A_CPU1_SA_DQ<12>
J 0
(-5790 4535);
DISPLAY 0.659574 (-5790 4535);
PAINT MONO (-5790 4535);
DISPLAY INVISIBLE (-5790 4535);
FORCEPROP 1 LASTPIN (-5800 4525) BN 12
J 0
(-5812 4533);
DISPLAY 0.489362 (-5812 4533);
PAINT GREEN (-5812 4533);
FORCEPROP 2 LAST CDS_LIB mstr_standard
J 0
(-5750 4525);
DISPLAY 0.723404 (-5750 4525);
PAINT MONO (-5750 4525);
DISPLAY INVISIBLE (-5750 4525);
FORCEPROP 1 LAST BODY_TYPE PLUMBING
J 0
(-5750 4575);
DISPLAY 0.872340 (-5750 4575);
PAINT GREEN (-5750 4575);
DISPLAY INVISIBLE (-5750 4575);
FORCEPROP 1 LAST HDL_TAP TRUE
J 0
(-5425 4400);
DISPLAY 0.872340 (-5425 4400);
DISPLAY INVISIBLE (-5425 4400);
FORCEPROP 1 LAST PATH I104
J 0
(-5752 4525);
DISPLAY 0.872340 (-5752 4525);
PAINT GREEN (-5752 4525);
DISPLAY INVISIBLE (-5752 4525);
FORCEADD TAP..1
(-5750 4475);
FORCEPROP 3 LASTPIN (-5800 4475) SIG_NAME M_A_CPU1_SA_DQ<11>
J 0
(-5790 4485);
DISPLAY 0.659574 (-5790 4485);
PAINT MONO (-5790 4485);
DISPLAY INVISIBLE (-5790 4485);
FORCEPROP 1 LASTPIN (-5800 4475) BN 11
J 0
(-5812 4483);
DISPLAY 0.489362 (-5812 4483);
PAINT GREEN (-5812 4483);
FORCEPROP 2 LAST CDS_LIB mstr_standard
J 0
(-5750 4475);
DISPLAY 0.723404 (-5750 4475);
PAINT MONO (-5750 4475);
DISPLAY INVISIBLE (-5750 4475);
FORCEPROP 1 LAST BODY_TYPE PLUMBING
J 0
(-5750 4525);
DISPLAY 0.872340 (-5750 4525);
PAINT GREEN (-5750 4525);
DISPLAY INVISIBLE (-5750 4525);
FORCEPROP 1 LAST HDL_TAP TRUE
J 0
(-5425 4350);
DISPLAY 0.872340 (-5425 4350);
DISPLAY INVISIBLE (-5425 4350);
FORCEPROP 1 LAST PATH I105
J 0
(-5752 4475);
DISPLAY 0.872340 (-5752 4475);
PAINT GREEN (-5752 4475);
DISPLAY INVISIBLE (-5752 4475);
FORCEADD TAP..1
(-5750 4425);
FORCEPROP 3 LASTPIN (-5800 4425) SIG_NAME M_A_CPU1_SA_DQ<10>
J 0
(-5790 4435);
DISPLAY 0.659574 (-5790 4435);
PAINT MONO (-5790 4435);
DISPLAY INVISIBLE (-5790 4435);
FORCEPROP 1 LASTPIN (-5800 4425) BN 10
J 0
(-5812 4433);
DISPLAY 0.489362 (-5812 4433);
PAINT GREEN (-5812 4433);
FORCEPROP 2 LAST CDS_LIB mstr_standard
J 0
(-5750 4425);
DISPLAY 0.723404 (-5750 4425);
PAINT MONO (-5750 4425);
DISPLAY INVISIBLE (-5750 4425);
FORCEPROP 1 LAST BODY_TYPE PLUMBING
J 0
(-5750 4475);
DISPLAY 0.872340 (-5750 4475);
PAINT GREEN (-5750 4475);
DISPLAY INVISIBLE (-5750 4475);
FORCEPROP 1 LAST HDL_TAP TRUE
J 0
(-5425 4300);
DISPLAY 0.872340 (-5425 4300);
DISPLAY INVISIBLE (-5425 4300);
FORCEPROP 1 LAST PATH I106
J 0
(-5752 4425);
DISPLAY 0.872340 (-5752 4425);
PAINT GREEN (-5752 4425);
DISPLAY INVISIBLE (-5752 4425);
FORCEADD TAP..1
(-5750 4575);
FORCEPROP 3 LASTPIN (-5800 4575) SIG_NAME M_A_CPU1_SA_DQ<13>
J 0
(-5790 4585);
DISPLAY 0.659574 (-5790 4585);
PAINT MONO (-5790 4585);
DISPLAY INVISIBLE (-5790 4585);
FORCEPROP 1 LASTPIN (-5800 4575) BN 13
J 0
(-5812 4583);
DISPLAY 0.489362 (-5812 4583);
PAINT GREEN (-5812 4583);
FORCEPROP 2 LAST CDS_LIB mstr_standard
J 0
(-5750 4575);
DISPLAY 0.723404 (-5750 4575);
PAINT MONO (-5750 4575);
DISPLAY INVISIBLE (-5750 4575);
FORCEPROP 1 LAST BODY_TYPE PLUMBING
J 0
(-5750 4625);
DISPLAY 0.872340 (-5750 4625);
PAINT GREEN (-5750 4625);
DISPLAY INVISIBLE (-5750 4625);
FORCEPROP 1 LAST HDL_TAP TRUE
J 0
(-5425 4450);
DISPLAY 0.872340 (-5425 4450);
DISPLAY INVISIBLE (-5425 4450);
FORCEPROP 1 LAST PATH I107
J 0
(-5752 4575);
DISPLAY 0.872340 (-5752 4575);
PAINT GREEN (-5752 4575);
DISPLAY INVISIBLE (-5752 4575);
FORCEADD TAP..1
(-5750 4625);
FORCEPROP 3 LASTPIN (-5800 4625) SIG_NAME M_A_CPU1_SA_DQ<14>
J 0
(-5790 4635);
DISPLAY 0.659574 (-5790 4635);
PAINT MONO (-5790 4635);
DISPLAY INVISIBLE (-5790 4635);
FORCEPROP 1 LASTPIN (-5800 4625) BN 14
J 0
(-5812 4633);
DISPLAY 0.489362 (-5812 4633);
PAINT GREEN (-5812 4633);
FORCEPROP 2 LAST CDS_LIB mstr_standard
J 0
(-5750 4625);
DISPLAY 0.723404 (-5750 4625);
PAINT MONO (-5750 4625);
DISPLAY INVISIBLE (-5750 4625);
FORCEPROP 1 LAST BODY_TYPE PLUMBING
J 0
(-5750 4675);
DISPLAY 0.872340 (-5750 4675);
PAINT GREEN (-5750 4675);
DISPLAY INVISIBLE (-5750 4675);
FORCEPROP 1 LAST HDL_TAP TRUE
J 0
(-5425 4500);
DISPLAY 0.872340 (-5425 4500);
DISPLAY INVISIBLE (-5425 4500);
FORCEPROP 1 LAST PATH I108
J 0
(-5752 4625);
DISPLAY 0.872340 (-5752 4625);
PAINT GREEN (-5752 4625);
DISPLAY INVISIBLE (-5752 4625);
FORCEADD TAP..1
(-5750 4775);
FORCEPROP 3 LASTPIN (-5800 4775) SIG_NAME M_A_CPU1_SA_DQ<17>
J 0
(-5790 4785);
DISPLAY 0.659574 (-5790 4785);
PAINT MONO (-5790 4785);
DISPLAY INVISIBLE (-5790 4785);
FORCEPROP 1 LASTPIN (-5800 4775) BN 17
J 0
(-5812 4783);
DISPLAY 0.489362 (-5812 4783);
PAINT GREEN (-5812 4783);
FORCEPROP 2 LAST CDS_LIB mstr_standard
J 0
(-5750 4775);
DISPLAY 0.723404 (-5750 4775);
PAINT MONO (-5750 4775);
DISPLAY INVISIBLE (-5750 4775);
FORCEPROP 1 LAST BODY_TYPE PLUMBING
J 0
(-5750 4825);
DISPLAY 0.872340 (-5750 4825);
PAINT GREEN (-5750 4825);
DISPLAY INVISIBLE (-5750 4825);
FORCEPROP 1 LAST HDL_TAP TRUE
J 0
(-5425 4650);
DISPLAY 0.872340 (-5425 4650);
DISPLAY INVISIBLE (-5425 4650);
FORCEPROP 1 LAST PATH I109
J 0
(-5752 4775);
DISPLAY 0.872340 (-5752 4775);
PAINT GREEN (-5752 4775);
DISPLAY INVISIBLE (-5752 4775);
FORCEADD OFFPAGE..6
(-8050 4125);
FORCEPROP 2 LAST $XR0 37 
J 0
(-8329 4125);
DISPLAY 0.638298 (-8329 4125);
PAINT MONO (-8329 4125);
FORCEPROP 2 LAST CDS_LIB mstr_standard
J 0
(-8050 4125);
DISPLAY 0.723404 (-8050 4125);
PAINT MONO (-8050 4125);
DISPLAY INVISIBLE (-8050 4125);
FORCEPROP 1 LAST OFFPAGE TRUE
J 0
(-7725 4000);
DISPLAY 0.872340 (-7725 4000);
PAINT GREEN (-7725 4000);
DISPLAY INVISIBLE (-7725 4000);
FORCEPROP 1 LAST COMMENT_BODY TRUE
J 0
(-7950 4050);
DISPLAY 0.872340 (-7950 4050);
PAINT GREEN (-7950 4050);
DISPLAY INVISIBLE (-7950 4050);
FORCEPROP 2 LAST PATH I11
J 0
(-8325 4175);
DISPLAY 1.021277 (-8325 4175);
DISPLAY INVISIBLE (-8325 4175);
FORCEADD TAP..1
(-5750 4725);
FORCEPROP 3 LASTPIN (-5800 4725) SIG_NAME M_A_CPU1_SA_DQ<16>
J 0
(-5790 4735);
DISPLAY 0.659574 (-5790 4735);
PAINT MONO (-5790 4735);
DISPLAY INVISIBLE (-5790 4735);
FORCEPROP 1 LASTPIN (-5800 4725) BN 16
J 0
(-5812 4733);
DISPLAY 0.489362 (-5812 4733);
PAINT GREEN (-5812 4733);
FORCEPROP 2 LAST CDS_LIB mstr_standard
J 0
(-5750 4725);
DISPLAY 0.723404 (-5750 4725);
PAINT MONO (-5750 4725);
DISPLAY INVISIBLE (-5750 4725);
FORCEPROP 1 LAST BODY_TYPE PLUMBING
J 0
(-5750 4775);
DISPLAY 0.872340 (-5750 4775);
PAINT GREEN (-5750 4775);
DISPLAY INVISIBLE (-5750 4775);
FORCEPROP 1 LAST HDL_TAP TRUE
J 0
(-5425 4600);
DISPLAY 0.872340 (-5425 4600);
DISPLAY INVISIBLE (-5425 4600);
FORCEPROP 1 LAST PATH I110
J 0
(-5752 4725);
DISPLAY 0.872340 (-5752 4725);
PAINT GREEN (-5752 4725);
DISPLAY INVISIBLE (-5752 4725);
FORCEADD TAP..1
(-5750 4675);
FORCEPROP 3 LASTPIN (-5800 4675) SIG_NAME M_A_CPU1_SA_DQ<15>
J 0
(-5790 4685);
DISPLAY 0.659574 (-5790 4685);
PAINT MONO (-5790 4685);
DISPLAY INVISIBLE (-5790 4685);
FORCEPROP 1 LASTPIN (-5800 4675) BN 15
J 0
(-5812 4683);
DISPLAY 0.489362 (-5812 4683);
PAINT GREEN (-5812 4683);
FORCEPROP 2 LAST CDS_LIB mstr_standard
J 0
(-5750 4675);
DISPLAY 0.723404 (-5750 4675);
PAINT MONO (-5750 4675);
DISPLAY INVISIBLE (-5750 4675);
FORCEPROP 1 LAST BODY_TYPE PLUMBING
J 0
(-5750 4725);
DISPLAY 0.872340 (-5750 4725);
PAINT GREEN (-5750 4725);
DISPLAY INVISIBLE (-5750 4725);
FORCEPROP 1 LAST HDL_TAP TRUE
J 0
(-5425 4550);
DISPLAY 0.872340 (-5425 4550);
DISPLAY INVISIBLE (-5425 4550);
FORCEPROP 1 LAST PATH I111
J 0
(-5752 4675);
DISPLAY 0.872340 (-5752 4675);
PAINT GREEN (-5752 4675);
DISPLAY INVISIBLE (-5752 4675);
FORCEADD TAP..1
(-5750 4825);
FORCEPROP 3 LASTPIN (-5800 4825) SIG_NAME M_A_CPU1_SA_DQ<18>
J 0
(-5790 4835);
DISPLAY 0.659574 (-5790 4835);
PAINT MONO (-5790 4835);
DISPLAY INVISIBLE (-5790 4835);
FORCEPROP 1 LASTPIN (-5800 4825) BN 18
J 0
(-5812 4833);
DISPLAY 0.489362 (-5812 4833);
PAINT GREEN (-5812 4833);
FORCEPROP 2 LAST CDS_LIB mstr_standard
J 0
(-5750 4825);
DISPLAY 0.723404 (-5750 4825);
PAINT MONO (-5750 4825);
DISPLAY INVISIBLE (-5750 4825);
FORCEPROP 1 LAST BODY_TYPE PLUMBING
J 0
(-5750 4875);
DISPLAY 0.872340 (-5750 4875);
PAINT GREEN (-5750 4875);
DISPLAY INVISIBLE (-5750 4875);
FORCEPROP 1 LAST HDL_TAP TRUE
J 0
(-5425 4700);
DISPLAY 0.872340 (-5425 4700);
DISPLAY INVISIBLE (-5425 4700);
FORCEPROP 1 LAST PATH I112
J 0
(-5752 4825);
DISPLAY 0.872340 (-5752 4825);
PAINT GREEN (-5752 4825);
DISPLAY INVISIBLE (-5752 4825);
FORCEADD TAP..1
(-5750 4875);
FORCEPROP 3 LASTPIN (-5800 4875) SIG_NAME M_A_CPU1_SA_DQ<19>
J 0
(-5790 4885);
DISPLAY 0.659574 (-5790 4885);
PAINT MONO (-5790 4885);
DISPLAY INVISIBLE (-5790 4885);
FORCEPROP 1 LASTPIN (-5800 4875) BN 19
J 0
(-5812 4883);
DISPLAY 0.489362 (-5812 4883);
PAINT GREEN (-5812 4883);
FORCEPROP 2 LAST CDS_LIB mstr_standard
J 0
(-5750 4875);
DISPLAY 0.723404 (-5750 4875);
PAINT MONO (-5750 4875);
DISPLAY INVISIBLE (-5750 4875);
FORCEPROP 1 LAST BODY_TYPE PLUMBING
J 0
(-5750 4925);
DISPLAY 0.872340 (-5750 4925);
PAINT GREEN (-5750 4925);
DISPLAY INVISIBLE (-5750 4925);
FORCEPROP 1 LAST HDL_TAP TRUE
J 0
(-5425 4750);
DISPLAY 0.872340 (-5425 4750);
DISPLAY INVISIBLE (-5425 4750);
FORCEPROP 1 LAST PATH I113
J 0
(-5752 4875);
DISPLAY 0.872340 (-5752 4875);
PAINT GREEN (-5752 4875);
DISPLAY INVISIBLE (-5752 4875);
FORCEADD TAP..1
(-5750 5025);
FORCEPROP 3 LASTPIN (-5800 5025) SIG_NAME M_A_CPU1_SA_DQ<22>
J 0
(-5790 5035);
DISPLAY 0.659574 (-5790 5035);
PAINT MONO (-5790 5035);
DISPLAY INVISIBLE (-5790 5035);
FORCEPROP 1 LASTPIN (-5800 5025) BN 22
J 0
(-5812 5033);
DISPLAY 0.489362 (-5812 5033);
PAINT GREEN (-5812 5033);
FORCEPROP 2 LAST CDS_LIB mstr_standard
J 0
(-5750 5025);
DISPLAY 0.723404 (-5750 5025);
PAINT MONO (-5750 5025);
DISPLAY INVISIBLE (-5750 5025);
FORCEPROP 1 LAST BODY_TYPE PLUMBING
J 0
(-5750 5075);
DISPLAY 0.872340 (-5750 5075);
PAINT GREEN (-5750 5075);
DISPLAY INVISIBLE (-5750 5075);
FORCEPROP 1 LAST HDL_TAP TRUE
J 0
(-5425 4900);
DISPLAY 0.872340 (-5425 4900);
DISPLAY INVISIBLE (-5425 4900);
FORCEPROP 1 LAST PATH I114
J 0
(-5752 5025);
DISPLAY 0.872340 (-5752 5025);
PAINT GREEN (-5752 5025);
DISPLAY INVISIBLE (-5752 5025);
FORCEADD TAP..1
(-5750 4975);
FORCEPROP 3 LASTPIN (-5800 4975) SIG_NAME M_A_CPU1_SA_DQ<21>
J 0
(-5790 4985);
DISPLAY 0.659574 (-5790 4985);
PAINT MONO (-5790 4985);
DISPLAY INVISIBLE (-5790 4985);
FORCEPROP 1 LASTPIN (-5800 4975) BN 21
J 0
(-5812 4983);
DISPLAY 0.489362 (-5812 4983);
PAINT GREEN (-5812 4983);
FORCEPROP 2 LAST CDS_LIB mstr_standard
J 0
(-5750 4975);
DISPLAY 0.723404 (-5750 4975);
PAINT MONO (-5750 4975);
DISPLAY INVISIBLE (-5750 4975);
FORCEPROP 1 LAST BODY_TYPE PLUMBING
J 0
(-5750 5025);
DISPLAY 0.872340 (-5750 5025);
PAINT GREEN (-5750 5025);
DISPLAY INVISIBLE (-5750 5025);
FORCEPROP 1 LAST HDL_TAP TRUE
J 0
(-5425 4850);
DISPLAY 0.872340 (-5425 4850);
DISPLAY INVISIBLE (-5425 4850);
FORCEPROP 1 LAST PATH I115
J 0
(-5752 4975);
DISPLAY 0.872340 (-5752 4975);
PAINT GREEN (-5752 4975);
DISPLAY INVISIBLE (-5752 4975);
FORCEADD TAP..1
(-5750 4925);
FORCEPROP 3 LASTPIN (-5800 4925) SIG_NAME M_A_CPU1_SA_DQ<20>
J 0
(-5790 4935);
DISPLAY 0.659574 (-5790 4935);
PAINT MONO (-5790 4935);
DISPLAY INVISIBLE (-5790 4935);
FORCEPROP 1 LASTPIN (-5800 4925) BN 20
J 0
(-5812 4933);
DISPLAY 0.489362 (-5812 4933);
PAINT GREEN (-5812 4933);
FORCEPROP 2 LAST CDS_LIB mstr_standard
J 0
(-5750 4925);
DISPLAY 0.723404 (-5750 4925);
PAINT MONO (-5750 4925);
DISPLAY INVISIBLE (-5750 4925);
FORCEPROP 1 LAST BODY_TYPE PLUMBING
J 0
(-5750 4975);
DISPLAY 0.872340 (-5750 4975);
PAINT GREEN (-5750 4975);
DISPLAY INVISIBLE (-5750 4975);
FORCEPROP 1 LAST HDL_TAP TRUE
J 0
(-5425 4800);
DISPLAY 0.872340 (-5425 4800);
DISPLAY INVISIBLE (-5425 4800);
FORCEPROP 1 LAST PATH I116
J 0
(-5752 4925);
DISPLAY 0.872340 (-5752 4925);
PAINT GREEN (-5752 4925);
DISPLAY INVISIBLE (-5752 4925);
FORCEADD TAP..1
(-5750 5125);
FORCEPROP 3 LASTPIN (-5800 5125) SIG_NAME M_A_CPU1_SA_DQ<24>
J 0
(-5790 5135);
DISPLAY 0.659574 (-5790 5135);
PAINT MONO (-5790 5135);
DISPLAY INVISIBLE (-5790 5135);
FORCEPROP 1 LASTPIN (-5800 5125) BN 24
J 0
(-5812 5133);
DISPLAY 0.489362 (-5812 5133);
PAINT GREEN (-5812 5133);
FORCEPROP 2 LAST CDS_LIB mstr_standard
J 0
(-5750 5125);
DISPLAY 0.723404 (-5750 5125);
PAINT MONO (-5750 5125);
DISPLAY INVISIBLE (-5750 5125);
FORCEPROP 1 LAST BODY_TYPE PLUMBING
J 0
(-5750 5175);
DISPLAY 0.872340 (-5750 5175);
PAINT GREEN (-5750 5175);
DISPLAY INVISIBLE (-5750 5175);
FORCEPROP 1 LAST HDL_TAP TRUE
J 0
(-5425 5000);
DISPLAY 0.872340 (-5425 5000);
DISPLAY INVISIBLE (-5425 5000);
FORCEPROP 1 LAST PATH I117
J 0
(-5752 5125);
DISPLAY 0.872340 (-5752 5125);
PAINT GREEN (-5752 5125);
DISPLAY INVISIBLE (-5752 5125);
FORCEADD TAP..1
(-5750 5075);
FORCEPROP 3 LASTPIN (-5800 5075) SIG_NAME M_A_CPU1_SA_DQ<23>
J 0
(-5790 5085);
DISPLAY 0.659574 (-5790 5085);
PAINT MONO (-5790 5085);
DISPLAY INVISIBLE (-5790 5085);
FORCEPROP 1 LASTPIN (-5800 5075) BN 23
J 0
(-5812 5083);
DISPLAY 0.489362 (-5812 5083);
PAINT GREEN (-5812 5083);
FORCEPROP 2 LAST CDS_LIB mstr_standard
J 0
(-5750 5075);
DISPLAY 0.723404 (-5750 5075);
PAINT MONO (-5750 5075);
DISPLAY INVISIBLE (-5750 5075);
FORCEPROP 1 LAST BODY_TYPE PLUMBING
J 0
(-5750 5125);
DISPLAY 0.872340 (-5750 5125);
PAINT GREEN (-5750 5125);
DISPLAY INVISIBLE (-5750 5125);
FORCEPROP 1 LAST HDL_TAP TRUE
J 0
(-5425 4950);
DISPLAY 0.872340 (-5425 4950);
DISPLAY INVISIBLE (-5425 4950);
FORCEPROP 1 LAST PATH I118
J 0
(-5752 5075);
DISPLAY 0.872340 (-5752 5075);
PAINT GREEN (-5752 5075);
DISPLAY INVISIBLE (-5752 5075);
FORCEADD TAP..1
(-5750 5225);
FORCEPROP 3 LASTPIN (-5800 5225) SIG_NAME M_A_CPU1_SA_DQ<26>
J 0
(-5790 5235);
DISPLAY 0.659574 (-5790 5235);
PAINT MONO (-5790 5235);
DISPLAY INVISIBLE (-5790 5235);
FORCEPROP 1 LASTPIN (-5800 5225) BN 26
J 0
(-5812 5233);
DISPLAY 0.489362 (-5812 5233);
PAINT GREEN (-5812 5233);
FORCEPROP 2 LAST CDS_LIB mstr_standard
J 0
(-5750 5225);
DISPLAY 0.723404 (-5750 5225);
PAINT MONO (-5750 5225);
DISPLAY INVISIBLE (-5750 5225);
FORCEPROP 1 LAST BODY_TYPE PLUMBING
J 0
(-5750 5275);
DISPLAY 0.872340 (-5750 5275);
PAINT GREEN (-5750 5275);
DISPLAY INVISIBLE (-5750 5275);
FORCEPROP 1 LAST HDL_TAP TRUE
J 0
(-5425 5100);
DISPLAY 0.872340 (-5425 5100);
DISPLAY INVISIBLE (-5425 5100);
FORCEPROP 1 LAST PATH I119
J 0
(-5752 5225);
DISPLAY 0.872340 (-5752 5225);
PAINT GREEN (-5752 5225);
DISPLAY INVISIBLE (-5752 5225);
FORCEADD OFFPAGE..1
(-8050 4175);
FORCEPROP 2 LAST $XR0 37 
J 0
(-8271 4175);
DISPLAY 0.638298 (-8271 4175);
PAINT MONO (-8271 4175);
FORCEPROP 2 LAST CDS_LIB mstr_standard
J 0
(-8050 4175);
DISPLAY 0.808511 (-8050 4175);
DISPLAY INVISIBLE (-8050 4175);
FORCEPROP 1 LAST OFFPAGE TRUE
J 0
(-7725 4050);
DISPLAY 0.872340 (-7725 4050);
PAINT GREEN (-7725 4050);
DISPLAY INVISIBLE (-7725 4050);
FORCEPROP 1 LAST COMMENT_BODY TRUE
J 0
(-7925 4075);
DISPLAY 0.872340 (-7925 4075);
PAINT GREEN (-7925 4075);
DISPLAY INVISIBLE (-7925 4075);
FORCEPROP 2 LAST PATH I12
J 0
(-8300 4225);
DISPLAY 1.021277 (-8300 4225);
DISPLAY INVISIBLE (-8300 4225);
FORCEADD TAP..1
(-5750 5275);
FORCEPROP 3 LASTPIN (-5800 5275) SIG_NAME M_A_CPU1_SA_DQ<27>
J 0
(-5790 5285);
DISPLAY 0.659574 (-5790 5285);
PAINT MONO (-5790 5285);
DISPLAY INVISIBLE (-5790 5285);
FORCEPROP 1 LASTPIN (-5800 5275) BN 27
J 0
(-5812 5283);
DISPLAY 0.489362 (-5812 5283);
PAINT GREEN (-5812 5283);
FORCEPROP 2 LAST CDS_LIB mstr_standard
J 0
(-5750 5275);
DISPLAY 0.723404 (-5750 5275);
PAINT MONO (-5750 5275);
DISPLAY INVISIBLE (-5750 5275);
FORCEPROP 1 LAST BODY_TYPE PLUMBING
J 0
(-5750 5325);
DISPLAY 0.872340 (-5750 5325);
PAINT GREEN (-5750 5325);
DISPLAY INVISIBLE (-5750 5325);
FORCEPROP 1 LAST HDL_TAP TRUE
J 0
(-5425 5150);
DISPLAY 0.872340 (-5425 5150);
DISPLAY INVISIBLE (-5425 5150);
FORCEPROP 1 LAST PATH I120
J 0
(-5752 5275);
DISPLAY 0.872340 (-5752 5275);
PAINT GREEN (-5752 5275);
DISPLAY INVISIBLE (-5752 5275);
FORCEADD TAP..1
(-5750 5175);
FORCEPROP 3 LASTPIN (-5800 5175) SIG_NAME M_A_CPU1_SA_DQ<25>
J 0
(-5790 5185);
DISPLAY 0.659574 (-5790 5185);
PAINT MONO (-5790 5185);
DISPLAY INVISIBLE (-5790 5185);
FORCEPROP 1 LASTPIN (-5800 5175) BN 25
J 0
(-5812 5183);
DISPLAY 0.489362 (-5812 5183);
PAINT GREEN (-5812 5183);
FORCEPROP 2 LAST CDS_LIB mstr_standard
J 0
(-5750 5175);
DISPLAY 0.723404 (-5750 5175);
PAINT MONO (-5750 5175);
DISPLAY INVISIBLE (-5750 5175);
FORCEPROP 1 LAST BODY_TYPE PLUMBING
J 0
(-5750 5225);
DISPLAY 0.872340 (-5750 5225);
PAINT GREEN (-5750 5225);
DISPLAY INVISIBLE (-5750 5225);
FORCEPROP 1 LAST HDL_TAP TRUE
J 0
(-5425 5050);
DISPLAY 0.872340 (-5425 5050);
DISPLAY INVISIBLE (-5425 5050);
FORCEPROP 1 LAST PATH I121
J 0
(-5752 5175);
DISPLAY 0.872340 (-5752 5175);
PAINT GREEN (-5752 5175);
DISPLAY INVISIBLE (-5752 5175);
FORCEADD TAP..1
(-5750 5425);
FORCEPROP 3 LASTPIN (-5800 5425) SIG_NAME M_A_CPU1_SA_DQ<30>
J 0
(-5790 5435);
DISPLAY 0.659574 (-5790 5435);
PAINT MONO (-5790 5435);
DISPLAY INVISIBLE (-5790 5435);
FORCEPROP 1 LASTPIN (-5800 5425) BN 30
J 0
(-5812 5433);
DISPLAY 0.489362 (-5812 5433);
PAINT GREEN (-5812 5433);
FORCEPROP 2 LAST CDS_LIB mstr_standard
J 0
(-5750 5425);
DISPLAY 0.723404 (-5750 5425);
PAINT MONO (-5750 5425);
DISPLAY INVISIBLE (-5750 5425);
FORCEPROP 1 LAST BODY_TYPE PLUMBING
J 0
(-5750 5475);
DISPLAY 0.872340 (-5750 5475);
PAINT GREEN (-5750 5475);
DISPLAY INVISIBLE (-5750 5475);
FORCEPROP 1 LAST HDL_TAP TRUE
J 0
(-5425 5300);
DISPLAY 0.872340 (-5425 5300);
DISPLAY INVISIBLE (-5425 5300);
FORCEPROP 1 LAST PATH I122
J 0
(-5752 5425);
DISPLAY 0.872340 (-5752 5425);
PAINT GREEN (-5752 5425);
DISPLAY INVISIBLE (-5752 5425);
FORCEADD TAP..1
(-5750 5325);
FORCEPROP 3 LASTPIN (-5800 5325) SIG_NAME M_A_CPU1_SA_DQ<28>
J 0
(-5790 5335);
DISPLAY 0.659574 (-5790 5335);
PAINT MONO (-5790 5335);
DISPLAY INVISIBLE (-5790 5335);
FORCEPROP 1 LASTPIN (-5800 5325) BN 28
J 0
(-5812 5333);
DISPLAY 0.489362 (-5812 5333);
PAINT GREEN (-5812 5333);
FORCEPROP 2 LAST CDS_LIB mstr_standard
J 0
(-5750 5325);
DISPLAY 0.723404 (-5750 5325);
PAINT MONO (-5750 5325);
DISPLAY INVISIBLE (-5750 5325);
FORCEPROP 1 LAST BODY_TYPE PLUMBING
J 0
(-5750 5375);
DISPLAY 0.872340 (-5750 5375);
PAINT GREEN (-5750 5375);
DISPLAY INVISIBLE (-5750 5375);
FORCEPROP 1 LAST HDL_TAP TRUE
J 0
(-5425 5200);
DISPLAY 0.872340 (-5425 5200);
DISPLAY INVISIBLE (-5425 5200);
FORCEPROP 1 LAST PATH I123
J 0
(-5752 5325);
DISPLAY 0.872340 (-5752 5325);
PAINT GREEN (-5752 5325);
DISPLAY INVISIBLE (-5752 5325);
FORCEADD TAP..1
(-5750 5375);
FORCEPROP 3 LASTPIN (-5800 5375) SIG_NAME M_A_CPU1_SA_DQ<29>
J 0
(-5790 5385);
DISPLAY 0.659574 (-5790 5385);
PAINT MONO (-5790 5385);
DISPLAY INVISIBLE (-5790 5385);
FORCEPROP 1 LASTPIN (-5800 5375) BN 29
J 0
(-5812 5383);
DISPLAY 0.489362 (-5812 5383);
PAINT GREEN (-5812 5383);
FORCEPROP 2 LAST CDS_LIB mstr_standard
J 0
(-5750 5375);
DISPLAY 0.723404 (-5750 5375);
PAINT MONO (-5750 5375);
DISPLAY INVISIBLE (-5750 5375);
FORCEPROP 1 LAST BODY_TYPE PLUMBING
J 0
(-5750 5425);
DISPLAY 0.872340 (-5750 5425);
PAINT GREEN (-5750 5425);
DISPLAY INVISIBLE (-5750 5425);
FORCEPROP 1 LAST HDL_TAP TRUE
J 0
(-5425 5250);
DISPLAY 0.872340 (-5425 5250);
DISPLAY INVISIBLE (-5425 5250);
FORCEPROP 1 LAST PATH I124
J 0
(-5752 5375);
DISPLAY 0.872340 (-5752 5375);
PAINT GREEN (-5752 5375);
DISPLAY INVISIBLE (-5752 5375);
FORCEADD TAP..1
(-5750 5475);
FORCEPROP 3 LASTPIN (-5800 5475) SIG_NAME M_A_CPU1_SA_DQ<31>
J 0
(-5790 5485);
DISPLAY 0.659574 (-5790 5485);
PAINT MONO (-5790 5485);
DISPLAY INVISIBLE (-5790 5485);
FORCEPROP 1 LASTPIN (-5800 5475) BN 31
J 0
(-5812 5483);
DISPLAY 0.489362 (-5812 5483);
PAINT GREEN (-5812 5483);
FORCEPROP 2 LAST CDS_LIB mstr_standard
J 0
(-5750 5475);
DISPLAY 0.723404 (-5750 5475);
PAINT MONO (-5750 5475);
DISPLAY INVISIBLE (-5750 5475);
FORCEPROP 1 LAST BODY_TYPE PLUMBING
J 0
(-5750 5525);
DISPLAY 0.872340 (-5750 5525);
PAINT GREEN (-5750 5525);
DISPLAY INVISIBLE (-5750 5525);
FORCEPROP 1 LAST HDL_TAP TRUE
J 0
(-5425 5350);
DISPLAY 0.872340 (-5425 5350);
DISPLAY INVISIBLE (-5425 5350);
FORCEPROP 1 LAST PATH I125
J 0
(-5752 5475);
DISPLAY 0.872340 (-5752 5475);
PAINT GREEN (-5752 5475);
DISPLAY INVISIBLE (-5752 5475);
FORCEADD OFFPAGE..3
(-5150 5525);
FORCEPROP 2 LAST $XR0 37 
J 0
(-4936 5525);
DISPLAY 0.638298 (-4936 5525);
PAINT MONO (-4936 5525);
FORCEPROP 2 LAST CDS_LIB mstr_standard
J 0
(-5150 5525);
DISPLAY 0.723404 (-5150 5525);
PAINT MONO (-5150 5525);
DISPLAY INVISIBLE (-5150 5525);
FORCEPROP 1 LAST OFFPAGE TRUE
J 0
(-4825 5400);
DISPLAY 0.872340 (-4825 5400);
PAINT GREEN (-4825 5400);
DISPLAY INVISIBLE (-4825 5400);
FORCEPROP 1 LAST COMMENT_BODY TRUE
J 0
(-5200 5425);
DISPLAY 0.872340 (-5200 5425);
PAINT GREEN (-5200 5425);
DISPLAY INVISIBLE (-5200 5425);
FORCEPROP 2 LAST PATH I126
J 0
(-4825 5575);
DISPLAY 1.021277 (-4825 5575);
DISPLAY INVISIBLE (-4825 5575);
FORCEADD OFFPAGE..5
(-6900 1475);
FORCEPROP 2 LAST $XR0 97 
J 0
(-7124 1475);
DISPLAY 0.638298 (-7124 1475);
PAINT MONO (-7124 1475);
FORCEPROP 2 LAST BOM_COST MEM
J 0
(-6975 1550);
DISPLAY 0.808511 (-6975 1550);
DISPLAY INVISIBLE (-6975 1550);
FORCEPROP 2 LAST CDS_LIB mstr_standard
J 0
(-6900 1475);
DISPLAY 0.808511 (-6900 1475);
DISPLAY INVISIBLE (-6900 1475);
FORCEPROP 1 LAST OFFPAGE TRUE
J 0
(-6575 1350);
DISPLAY 0.872340 (-6575 1350);
PAINT GREEN (-6575 1350);
DISPLAY INVISIBLE (-6575 1350);
FORCEPROP 1 LAST COMMENT_BODY TRUE
J 0
(-6800 1400);
DISPLAY 0.872340 (-6800 1400);
PAINT GREEN (-6800 1400);
DISPLAY INVISIBLE (-6800 1400);
FORCEPROP 2 LAST PATH I127
J 0
(-7100 1525);
DISPLAY 1.021277 (-7100 1525);
DISPLAY INVISIBLE (-7100 1525);
FORCEADD GND..1
(-6125 1075);
FORCEPROP 3 LASTPIN (-6125 1125) SIG_NAME GND\g
J 0
(-6115 1135);
DISPLAY 0.659574 (-6115 1135);
PAINT MONO (-6115 1135);
DISPLAY INVISIBLE (-6115 1135);
FORCEPROP 2 LAST BOM_COST MEM
J 0
(-6225 1150);
DISPLAY 0.808511 (-6225 1150);
DISPLAY INVISIBLE (-6225 1150);
FORCEPROP 2 LAST CDS_LIB mstr_symbols
J 0
(-6125 1075);
DISPLAY 0.808511 (-6125 1075);
DISPLAY INVISIBLE (-6125 1075);
FORCEPROP 1 LAST SIZE 1B
J 0
(-6050 1025);
DISPLAY 0.851064 (-6050 1025);
PAINT GREEN (-6050 1025);
DISPLAY INVISIBLE (-6050 1025);
FORCEPROP 1 LAST BODY_TYPE PLUMBING
J 0
(-6170 1032);
DISPLAY 0.340426 (-6170 1032);
PAINT GREEN (-6170 1032);
DISPLAY INVISIBLE (-6170 1032);
FORCEPROP 1 LAST PATH I128
J 0
(-6050 1075);
DISPLAY 0.872340 (-6050 1075);
PAINT AQUA (-6050 1075);
DISPLAY INVISIBLE (-6050 1075);
FORCEPROP 1 LAST VOLTAGE 0.0
J 0
(-6170 1032);
DISPLAY 0.723404 (-6170 1032);
PAINT SKYBLUE (-6170 1032);
DISPLAY INVISIBLE (-6170 1032);
FORCEPROP 1 LAST HDL_POWER GND
J 0
(-6125 1225);
DISPLAY 0.851064 (-6125 1225);
PAINT GREEN (-6125 1225);
DISPLAY INVISIBLE (-6125 1225);
FORCEADD Q_RES..2
(-6125 1300);
FORCEPROP 1 LAST LOCATION R36
J 0
(-6080 1425);
DISPLAY 0.489362 (-6080 1425);
PAINT SKYBLUE (-6080 1425);
FORCEPROP 2 LAST SEC 1
J 0
(-6075 1525);
DISPLAY 0.808511 (-6075 1525);
PAINT MONO (-6075 1525);
DISPLAY INVISIBLE (-6075 1525);
FORCEPROP 1 LASTPIN (-6125 1400) $PN 1
J 0
(-6120 1362);
DISPLAY 0.489362 (-6120 1362);
PAINT WHITE (-6120 1362);
FORCEPROP 1 LASTPIN (-6125 1200) $PN 2
J 0
(-6120 1210);
DISPLAY 0.489362 (-6120 1210);
PAINT WHITE (-6120 1210);
FORCEPROP 0 LASTPIN (-6125 1400) XNET_PINS 3
R 1
J 0
(-6135 1410);
DISPLAY 0.808511 (-6135 1410);
PAINT MONO (-6135 1410);
DISPLAY INVISIBLE (-6135 1410);
FORCEPROP 0 LASTPIN (-6125 1200) XNET_PINS 2
R 1
J 2
(-6135 1190);
DISPLAY 0.808511 (-6135 1190);
PAINT MONO (-6135 1190);
DISPLAY INVISIBLE (-6135 1190);
FORCEPROP 1 LAST WATTAGE 1/16W
J 0
(-6085 1275);
DISPLAY 0.489362 (-6085 1275);
PAINT SKYBLUE (-6085 1275);
FORCEPROP 1 LAST MATERIAL CHIP
J 0
(-6085 1225);
DISPLAY 0.489362 (-6085 1225);
PAINT SKYBLUE (-6085 1225);
FORCEPROP 1 LAST TOLERANCE 1%
J 0
(-6080 1325);
DISPLAY 0.489362 (-6080 1325);
PAINT SKYBLUE (-6080 1325);
FORCEPROP 1 LAST VALUE 10K
J 0
(-6080 1375);
DISPLAY 0.489362 (-6080 1375);
PAINT SKYBLUE (-6080 1375);
FORCEPROP 1 LAST PART_NUMBER CS31002FB08
J 0
(-6085 1175);
DISPLAY 0.489362 (-6085 1175);
PAINT SKYBLUE (-6085 1175);
FORCEPROP 1 LAST PACK_TYPE 0402LF
J 0
(-6085 1125);
DISPLAY 0.489362 (-6085 1125);
PAINT SKYBLUE (-6085 1125);
FORCEPROP 2 LAST SEC_TYPE 0402LF
J 0
(-6075 1525);
DISPLAY 0.808511 (-6075 1525);
PAINT MONO (-6075 1525);
DISPLAY INVISIBLE (-6075 1525);
FORCEPROP 2 LAST CDS_LIB pure_quanta
J 0
(-6125 1300);
DISPLAY INVISIBLE (-6125 1300);
FORCEPROP 2 LAST BOM_COST MEM
J 0
(-6075 1475);
DISPLAY 0.808511 (-6075 1475);
DISPLAY INVISIBLE (-6075 1475);
FORCEPROP 1 LAST PATH I129
J 0
(-6075 1475);
DISPLAY 0.978723 (-6075 1475);
PAINT WHITE (-6075 1475);
DISPLAY INVISIBLE (-6075 1475);
FORCEPROP 2 LAST ROOM MEM_CH_A_CPU1_DIMM1
J 0
(-6075 1525);
DISPLAY 0.808511 (-6075 1525);
PAINT RED (-6075 1525);
DISPLAY INVISIBLE (-6075 1525);
FORCEADD OFFPAGE..1
(-8050 4325);
FORCEPROP 2 LAST $XR0 37 
J 0
(-8271 4325);
DISPLAY 0.638298 (-8271 4325);
PAINT MONO (-8271 4325);
FORCEPROP 2 LAST CDS_LIB mstr_standard
J 0
(-8050 4325);
DISPLAY 0.808511 (-8050 4325);
DISPLAY INVISIBLE (-8050 4325);
FORCEPROP 1 LAST OFFPAGE TRUE
J 0
(-7725 4200);
DISPLAY 0.872340 (-7725 4200);
PAINT GREEN (-7725 4200);
DISPLAY INVISIBLE (-7725 4200);
FORCEPROP 1 LAST COMMENT_BODY TRUE
J 0
(-7925 4225);
DISPLAY 0.872340 (-7925 4225);
PAINT GREEN (-7925 4225);
DISPLAY INVISIBLE (-7925 4225);
FORCEPROP 2 LAST PATH I13
J 0
(-8000 4400);
DISPLAY 1.021277 (-8000 4400);
DISPLAY INVISIBLE (-8000 4400);
FORCEADD GND..1
(-2100 2075);
FORCEPROP 3 LASTPIN (-2100 2125) SIG_NAME GND\g
J 0
(-2090 2135);
DISPLAY 0.659574 (-2090 2135);
PAINT MONO (-2090 2135);
DISPLAY INVISIBLE (-2090 2135);
FORCEPROP 2 LAST CDS_LIB mstr_symbols
J 0
(-2100 2075);
DISPLAY 0.723404 (-2100 2075);
DISPLAY INVISIBLE (-2100 2075);
FORCEPROP 1 LAST SIZE 1B
J 0
(-2025 2025);
DISPLAY 0.851064 (-2025 2025);
PAINT GREEN (-2025 2025);
DISPLAY INVISIBLE (-2025 2025);
FORCEPROP 1 LAST BODY_TYPE PLUMBING
J 0
(-2145 2032);
DISPLAY 0.340426 (-2145 2032);
PAINT GREEN (-2145 2032);
DISPLAY INVISIBLE (-2145 2032);
FORCEPROP 1 LAST PATH I130
J 0
(-2025 2075);
DISPLAY 0.872340 (-2025 2075);
PAINT AQUA (-2025 2075);
DISPLAY INVISIBLE (-2025 2075);
FORCEPROP 1 LAST VOLTAGE 0.0
J 0
(-2145 2032);
DISPLAY 0.723404 (-2145 2032);
PAINT SKYBLUE (-2145 2032);
DISPLAY INVISIBLE (-2145 2032);
FORCEPROP 1 LAST HDL_POWER GND
J 0
(-2100 2225);
DISPLAY 0.851064 (-2100 2225);
PAINT GREEN (-2100 2225);
DISPLAY INVISIBLE (-2100 2225);
FORCEADD OFFPAGE..1
(-8050 4375);
FORCEPROP 2 LAST $XR0 37 
J 0
(-8271 4375);
DISPLAY 0.638298 (-8271 4375);
PAINT MONO (-8271 4375);
FORCEPROP 2 LAST CDS_LIB mstr_standard
J 0
(-8050 4375);
DISPLAY 0.723404 (-8050 4375);
PAINT MONO (-8050 4375);
DISPLAY INVISIBLE (-8050 4375);
FORCEPROP 1 LAST OFFPAGE TRUE
J 0
(-7725 4250);
DISPLAY 0.872340 (-7725 4250);
PAINT GREEN (-7725 4250);
DISPLAY INVISIBLE (-7725 4250);
FORCEPROP 1 LAST COMMENT_BODY TRUE
J 0
(-7925 4275);
DISPLAY 0.872340 (-7925 4275);
PAINT GREEN (-7925 4275);
DISPLAY INVISIBLE (-7925 4275);
FORCEPROP 2 LAST PATH I14
J 0
(-8000 4450);
DISPLAY 1.021277 (-8000 4450);
DISPLAY INVISIBLE (-8000 4450);
FORCEADD GND..1
(-500 1875);
FORCEPROP 3 LASTPIN (-500 1925) SIG_NAME GND\g
J 0
(-490 1935);
DISPLAY 0.659574 (-490 1935);
PAINT MONO (-490 1935);
DISPLAY INVISIBLE (-490 1935);
FORCEPROP 2 LAST CDS_LIB mstr_symbols
J 0
(-500 1875);
DISPLAY 0.723404 (-500 1875);
DISPLAY INVISIBLE (-500 1875);
FORCEPROP 1 LAST SIZE 1B
J 0
(-425 1825);
DISPLAY 0.851064 (-425 1825);
PAINT GREEN (-425 1825);
DISPLAY INVISIBLE (-425 1825);
FORCEPROP 1 LAST BODY_TYPE PLUMBING
J 0
(-545 1832);
DISPLAY 0.340426 (-545 1832);
PAINT GREEN (-545 1832);
DISPLAY INVISIBLE (-545 1832);
FORCEPROP 1 LAST PATH I146
J 0
(-425 1875);
DISPLAY 0.872340 (-425 1875);
PAINT AQUA (-425 1875);
DISPLAY INVISIBLE (-425 1875);
FORCEPROP 1 LAST VOLTAGE 0.0
J 0
(-545 1832);
DISPLAY 0.723404 (-545 1832);
PAINT SKYBLUE (-545 1832);
DISPLAY INVISIBLE (-545 1832);
FORCEPROP 1 LAST HDL_POWER GND
J 0
(-500 2025);
DISPLAY 0.851064 (-500 2025);
PAINT GREEN (-500 2025);
DISPLAY INVISIBLE (-500 2025);
FORCEADD OFFPAGE..1
(-8050 4225);
FORCEPROP 2 LAST $XR0 37 
J 0
(-8271 4225);
DISPLAY 0.638298 (-8271 4225);
PAINT MONO (-8271 4225);
FORCEPROP 2 LAST CDS_LIB mstr_standard
J 0
(-8050 4225);
DISPLAY 0.723404 (-8050 4225);
PAINT MONO (-8050 4225);
DISPLAY INVISIBLE (-8050 4225);
FORCEPROP 1 LAST OFFPAGE TRUE
J 0
(-7725 4100);
DISPLAY 0.872340 (-7725 4100);
PAINT GREEN (-7725 4100);
DISPLAY INVISIBLE (-7725 4100);
FORCEPROP 1 LAST COMMENT_BODY TRUE
J 0
(-7925 4125);
DISPLAY 0.872340 (-7925 4125);
PAINT GREEN (-7925 4125);
DISPLAY INVISIBLE (-7925 4125);
FORCEPROP 2 LAST PATH I15
J 0
(-8300 4275);
DISPLAY 1.021277 (-8300 4275);
DISPLAY INVISIBLE (-8300 4275);
FORCEADD OFFPAGE..1
(-8050 4625);
FORCEPROP 2 LAST $XR0 37 
J 0
(-8271 4625);
DISPLAY 0.638298 (-8271 4625);
PAINT MONO (-8271 4625);
FORCEPROP 2 LAST CDS_LIB mstr_standard
J 0
(-8050 4625);
DISPLAY 0.808511 (-8050 4625);
DISPLAY INVISIBLE (-8050 4625);
FORCEPROP 1 LAST OFFPAGE TRUE
J 0
(-7725 4500);
DISPLAY 0.872340 (-7725 4500);
PAINT GREEN (-7725 4500);
DISPLAY INVISIBLE (-7725 4500);
FORCEPROP 1 LAST COMMENT_BODY TRUE
J 0
(-7925 4525);
DISPLAY 0.872340 (-7925 4525);
PAINT GREEN (-7925 4525);
DISPLAY INVISIBLE (-7925 4525);
FORCEPROP 2 LAST PATH I16
J 0
(-8300 4675);
DISPLAY 1.021277 (-8300 4675);
DISPLAY INVISIBLE (-8300 4675);
FORCEADD OFFPAGE..1
(-8050 4475);
FORCEPROP 2 LAST $XR0 37 
J 0
(-8271 4475);
DISPLAY 0.638298 (-8271 4475);
PAINT MONO (-8271 4475);
FORCEPROP 2 LAST CDS_LIB mstr_standard
J 0
(-8050 4475);
DISPLAY 0.808511 (-8050 4475);
DISPLAY INVISIBLE (-8050 4475);
FORCEPROP 1 LAST OFFPAGE TRUE
J 0
(-7725 4350);
DISPLAY 0.872340 (-7725 4350);
PAINT GREEN (-7725 4350);
DISPLAY INVISIBLE (-7725 4350);
FORCEPROP 1 LAST COMMENT_BODY TRUE
J 0
(-7925 4375);
DISPLAY 0.872340 (-7925 4375);
PAINT GREEN (-7925 4375);
DISPLAY INVISIBLE (-7925 4375);
FORCEPROP 2 LAST PATH I17
J 0
(-8300 4525);
DISPLAY 1.021277 (-8300 4525);
DISPLAY INVISIBLE (-8300 4525);
FORCEADD SCONN288_DDR506112002KQ..3
(-1300 3825);
FORCEPROP 1 LAST LOCATION J24
J 0
(-1750 5800);
DISPLAY 0.468085 (-1750 5800);
PAINT SKYBLUE (-1750 5800);
FORCEPROP 0 LAST $SEC 3
J 0
(-1750 5950);
DISPLAY 0.680851 (-1750 5950);
PAINT MONO (-1750 5950);
DISPLAY INVISIBLE (-1750 5950);
FORCEPROP 0 LAST CDS_SEC 3
J 0
(-1750 5950);
DISPLAY 0.680851 (-1750 5950);
DISPLAY INVISIBLE (-1750 5950);
FORCEPROP 0 LASTPIN (-700 2225) $PN G1
J 0
(-690 2235);
DISPLAY 0.680851 (-690 2235);
PAINT MONO (-690 2235);
FORCEPROP 0 LASTPIN (-700 2175) $PN G2
J 0
(-690 2185);
DISPLAY 0.680851 (-690 2185);
PAINT MONO (-690 2185);
FORCEPROP 0 LASTPIN (-700 2125) $PN G3
J 0
(-690 2135);
DISPLAY 0.680851 (-690 2135);
PAINT MONO (-690 2135);
FORCEPROP 0 LASTPIN (-1900 5375) $PN 1
J 2
(-1910 5385);
DISPLAY 0.680851 (-1910 5385);
PAINT MONO (-1910 5385);
FORCEPROP 0 LASTPIN (-1900 5425) $PN 145
J 2
(-1910 5435);
DISPLAY 0.680851 (-1910 5435);
PAINT MONO (-1910 5435);
FORCEPROP 0 LASTPIN (-1900 5475) $PN 146
J 2
(-1910 5485);
DISPLAY 0.680851 (-1910 5485);
PAINT MONO (-1910 5485);
FORCEPROP 0 LASTPIN (-700 2325) $PN 6
J 0
(-690 2335);
DISPLAY 0.680851 (-690 2335);
PAINT MONO (-690 2335);
FORCEPROP 0 LASTPIN (-700 2375) $PN 8
J 0
(-690 2385);
DISPLAY 0.680851 (-690 2385);
PAINT MONO (-690 2385);
FORCEPROP 0 LASTPIN (-700 2425) $PN 10
J 0
(-690 2435);
DISPLAY 0.680851 (-690 2435);
PAINT MONO (-690 2435);
FORCEPROP 0 LASTPIN (-700 2475) $PN 13
J 0
(-690 2485);
DISPLAY 0.680851 (-690 2485);
PAINT MONO (-690 2485);
FORCEPROP 0 LASTPIN (-700 2525) $PN 15
J 0
(-690 2535);
DISPLAY 0.680851 (-690 2535);
PAINT MONO (-690 2535);
FORCEPROP 0 LASTPIN (-700 2575) $PN 17
J 0
(-690 2585);
DISPLAY 0.680851 (-690 2585);
PAINT MONO (-690 2585);
FORCEPROP 0 LASTPIN (-700 2625) $PN 19
J 0
(-690 2635);
DISPLAY 0.680851 (-690 2635);
PAINT MONO (-690 2635);
FORCEPROP 0 LASTPIN (-700 2675) $PN 21
J 0
(-690 2685);
DISPLAY 0.680851 (-690 2685);
PAINT MONO (-690 2685);
FORCEPROP 0 LASTPIN (-700 2725) $PN 24
J 0
(-690 2735);
DISPLAY 0.680851 (-690 2735);
PAINT MONO (-690 2735);
FORCEPROP 0 LASTPIN (-700 2775) $PN 26
J 0
(-690 2785);
DISPLAY 0.680851 (-690 2785);
PAINT MONO (-690 2785);
FORCEPROP 0 LASTPIN (-700 2825) $PN 28
J 0
(-690 2835);
DISPLAY 0.680851 (-690 2835);
PAINT MONO (-690 2835);
FORCEPROP 0 LASTPIN (-700 2875) $PN 30
J 0
(-690 2885);
DISPLAY 0.680851 (-690 2885);
PAINT MONO (-690 2885);
FORCEPROP 0 LASTPIN (-700 2925) $PN 32
J 0
(-690 2935);
DISPLAY 0.680851 (-690 2935);
PAINT MONO (-690 2935);
FORCEPROP 0 LASTPIN (-700 2975) $PN 35
J 0
(-690 2985);
DISPLAY 0.680851 (-690 2985);
PAINT MONO (-690 2985);
FORCEPROP 0 LASTPIN (-700 3025) $PN 37
J 0
(-690 3035);
DISPLAY 0.680851 (-690 3035);
PAINT MONO (-690 3035);
FORCEPROP 0 LASTPIN (-700 3075) $PN 39
J 0
(-690 3085);
DISPLAY 0.680851 (-690 3085);
PAINT MONO (-690 3085);
FORCEPROP 0 LASTPIN (-700 3125) $PN 41
J 0
(-690 3135);
DISPLAY 0.680851 (-690 3135);
PAINT MONO (-690 3135);
FORCEPROP 0 LASTPIN (-700 3175) $PN 43
J 0
(-690 3185);
DISPLAY 0.680851 (-690 3185);
PAINT MONO (-690 3185);
FORCEPROP 0 LASTPIN (-700 3225) $PN 46
J 0
(-690 3235);
DISPLAY 0.680851 (-690 3235);
PAINT MONO (-690 3235);
FORCEPROP 0 LASTPIN (-700 3275) $PN 48
J 0
(-690 3285);
DISPLAY 0.680851 (-690 3285);
PAINT MONO (-690 3285);
FORCEPROP 0 LASTPIN (-700 3325) $PN 50
J 0
(-690 3335);
DISPLAY 0.680851 (-690 3335);
PAINT MONO (-690 3335);
FORCEPROP 0 LASTPIN (-700 3375) $PN 52
J 0
(-690 3385);
DISPLAY 0.680851 (-690 3385);
PAINT MONO (-690 3385);
FORCEPROP 0 LASTPIN (-700 3425) $PN 54
J 0
(-690 3435);
DISPLAY 0.680851 (-690 3435);
PAINT MONO (-690 3435);
FORCEPROP 0 LASTPIN (-700 3475) $PN 57
J 0
(-690 3485);
DISPLAY 0.680851 (-690 3485);
PAINT MONO (-690 3485);
FORCEPROP 0 LASTPIN (-700 3525) $PN 59
J 0
(-690 3535);
DISPLAY 0.680851 (-690 3535);
PAINT MONO (-690 3535);
FORCEPROP 0 LASTPIN (-700 3575) $PN 61
J 0
(-690 3585);
DISPLAY 0.680851 (-690 3585);
PAINT MONO (-690 3585);
FORCEPROP 0 LASTPIN (-700 3625) $PN 63
J 0
(-690 3635);
DISPLAY 0.680851 (-690 3635);
PAINT MONO (-690 3635);
FORCEPROP 0 LASTPIN (-700 3675) $PN 65
J 0
(-690 3685);
DISPLAY 0.680851 (-690 3685);
PAINT MONO (-690 3685);
FORCEPROP 0 LASTPIN (-700 3725) $PN 67
J 0
(-690 3735);
DISPLAY 0.680851 (-690 3735);
PAINT MONO (-690 3735);
FORCEPROP 0 LASTPIN (-700 3775) $PN 69
J 0
(-690 3785);
DISPLAY 0.680851 (-690 3785);
PAINT MONO (-690 3785);
FORCEPROP 0 LASTPIN (-700 3825) $PN 71
J 0
(-690 3835);
DISPLAY 0.680851 (-690 3835);
PAINT MONO (-690 3835);
FORCEPROP 0 LASTPIN (-700 3875) $PN 73
J 0
(-690 3885);
DISPLAY 0.680851 (-690 3885);
PAINT MONO (-690 3885);
FORCEPROP 0 LASTPIN (-700 3925) $PN 75
J 0
(-690 3935);
DISPLAY 0.680851 (-690 3935);
PAINT MONO (-690 3935);
FORCEPROP 0 LASTPIN (-700 3975) $PN 77
J 0
(-690 3985);
DISPLAY 0.680851 (-690 3985);
PAINT MONO (-690 3985);
FORCEPROP 0 LASTPIN (-700 4025) $PN 79
J 0
(-690 4035);
DISPLAY 0.680851 (-690 4035);
PAINT MONO (-690 4035);
FORCEPROP 0 LASTPIN (-700 4075) $PN 81
J 0
(-690 4085);
DISPLAY 0.680851 (-690 4085);
PAINT MONO (-690 4085);
FORCEPROP 0 LASTPIN (-700 4125) $PN 83
J 0
(-690 4135);
DISPLAY 0.680851 (-690 4135);
PAINT MONO (-690 4135);
FORCEPROP 0 LASTPIN (-700 4175) $PN 85
J 0
(-690 4185);
DISPLAY 0.680851 (-690 4185);
PAINT MONO (-690 4185);
FORCEPROP 0 LASTPIN (-700 4225) $PN 88
J 0
(-690 4235);
DISPLAY 0.680851 (-690 4235);
PAINT MONO (-690 4235);
FORCEPROP 0 LASTPIN (-700 4275) $PN 90
J 0
(-690 4285);
DISPLAY 0.680851 (-690 4285);
PAINT MONO (-690 4285);
FORCEPROP 0 LASTPIN (-700 4325) $PN 92
J 0
(-690 4335);
DISPLAY 0.680851 (-690 4335);
PAINT MONO (-690 4335);
FORCEPROP 0 LASTPIN (-700 4375) $PN 95
J 0
(-690 4385);
DISPLAY 0.680851 (-690 4385);
PAINT MONO (-690 4385);
FORCEPROP 0 LASTPIN (-700 4425) $PN 97
J 0
(-690 4435);
DISPLAY 0.680851 (-690 4435);
PAINT MONO (-690 4435);
FORCEPROP 0 LASTPIN (-700 4475) $PN 99
J 0
(-690 4485);
DISPLAY 0.680851 (-690 4485);
PAINT MONO (-690 4485);
FORCEPROP 0 LASTPIN (-700 4525) $PN 101
J 0
(-690 4535);
DISPLAY 0.680851 (-690 4535);
PAINT MONO (-690 4535);
FORCEPROP 0 LASTPIN (-700 4575) $PN 103
J 0
(-690 4585);
DISPLAY 0.680851 (-690 4585);
PAINT MONO (-690 4585);
FORCEPROP 0 LASTPIN (-700 4625) $PN 106
J 0
(-690 4635);
DISPLAY 0.680851 (-690 4635);
PAINT MONO (-690 4635);
FORCEPROP 0 LASTPIN (-700 4675) $PN 108
J 0
(-690 4685);
DISPLAY 0.680851 (-690 4685);
PAINT MONO (-690 4685);
FORCEPROP 0 LASTPIN (-700 4725) $PN 110
J 0
(-690 4735);
DISPLAY 0.680851 (-690 4735);
PAINT MONO (-690 4735);
FORCEPROP 0 LASTPIN (-700 4775) $PN 112
J 0
(-690 4785);
DISPLAY 0.680851 (-690 4785);
PAINT MONO (-690 4785);
FORCEPROP 0 LASTPIN (-700 4825) $PN 114
J 0
(-690 4835);
DISPLAY 0.680851 (-690 4835);
PAINT MONO (-690 4835);
FORCEPROP 0 LASTPIN (-700 4875) $PN 117
J 0
(-690 4885);
DISPLAY 0.680851 (-690 4885);
PAINT MONO (-690 4885);
FORCEPROP 0 LASTPIN (-700 4925) $PN 119
J 0
(-690 4935);
DISPLAY 0.680851 (-690 4935);
PAINT MONO (-690 4935);
FORCEPROP 0 LASTPIN (-700 4975) $PN 121
J 0
(-690 4985);
DISPLAY 0.680851 (-690 4985);
PAINT MONO (-690 4985);
FORCEPROP 0 LASTPIN (-700 5025) $PN 123
J 0
(-690 5035);
DISPLAY 0.680851 (-690 5035);
PAINT MONO (-690 5035);
FORCEPROP 0 LASTPIN (-700 5075) $PN 125
J 0
(-690 5085);
DISPLAY 0.680851 (-690 5085);
PAINT MONO (-690 5085);
FORCEPROP 0 LASTPIN (-700 5125) $PN 128
J 0
(-690 5135);
DISPLAY 0.680851 (-690 5135);
PAINT MONO (-690 5135);
FORCEPROP 0 LASTPIN (-700 5175) $PN 130
J 0
(-690 5185);
DISPLAY 0.680851 (-690 5185);
PAINT MONO (-690 5185);
FORCEPROP 0 LASTPIN (-700 5225) $PN 132
J 0
(-690 5235);
DISPLAY 0.680851 (-690 5235);
PAINT MONO (-690 5235);
FORCEPROP 0 LASTPIN (-700 5275) $PN 134
J 0
(-690 5285);
DISPLAY 0.680851 (-690 5285);
PAINT MONO (-690 5285);
FORCEPROP 0 LASTPIN (-700 5325) $PN 136
J 0
(-690 5335);
DISPLAY 0.680851 (-690 5335);
PAINT MONO (-690 5335);
FORCEPROP 0 LASTPIN (-700 5375) $PN 139
J 0
(-690 5385);
DISPLAY 0.680851 (-690 5385);
PAINT MONO (-690 5385);
FORCEPROP 0 LASTPIN (-700 5425) $PN 141
J 0
(-690 5435);
DISPLAY 0.680851 (-690 5435);
PAINT MONO (-690 5435);
FORCEPROP 0 LASTPIN (-700 5475) $PN 143
J 0
(-690 5485);
DISPLAY 0.680851 (-690 5485);
PAINT MONO (-690 5485);
FORCEPROP 0 LASTPIN (-1900 2225) $PN 151
J 2
(-1910 2235);
DISPLAY 0.680851 (-1910 2235);
PAINT MONO (-1910 2235);
FORCEPROP 0 LASTPIN (-1900 2275) $PN 153
J 2
(-1910 2285);
DISPLAY 0.680851 (-1910 2285);
PAINT MONO (-1910 2285);
FORCEPROP 0 LASTPIN (-1900 2325) $PN 155
J 2
(-1910 2335);
DISPLAY 0.680851 (-1910 2335);
PAINT MONO (-1910 2335);
FORCEPROP 0 LASTPIN (-1900 2375) $PN 158
J 2
(-1910 2385);
DISPLAY 0.680851 (-1910 2385);
PAINT MONO (-1910 2385);
FORCEPROP 0 LASTPIN (-1900 2425) $PN 160
J 2
(-1910 2435);
DISPLAY 0.680851 (-1910 2435);
PAINT MONO (-1910 2435);
FORCEPROP 0 LASTPIN (-1900 2475) $PN 162
J 2
(-1910 2485);
DISPLAY 0.680851 (-1910 2485);
PAINT MONO (-1910 2485);
FORCEPROP 0 LASTPIN (-1900 2525) $PN 164
J 2
(-1910 2535);
DISPLAY 0.680851 (-1910 2535);
PAINT MONO (-1910 2535);
FORCEPROP 0 LASTPIN (-1900 2575) $PN 166
J 2
(-1910 2585);
DISPLAY 0.680851 (-1910 2585);
PAINT MONO (-1910 2585);
FORCEPROP 0 LASTPIN (-1900 2625) $PN 169
J 2
(-1910 2635);
DISPLAY 0.680851 (-1910 2635);
PAINT MONO (-1910 2635);
FORCEPROP 0 LASTPIN (-1900 2675) $PN 171
J 2
(-1910 2685);
DISPLAY 0.680851 (-1910 2685);
PAINT MONO (-1910 2685);
FORCEPROP 0 LASTPIN (-1900 2725) $PN 173
J 2
(-1910 2735);
DISPLAY 0.680851 (-1910 2735);
PAINT MONO (-1910 2735);
FORCEPROP 0 LASTPIN (-1900 2775) $PN 175
J 2
(-1910 2785);
DISPLAY 0.680851 (-1910 2785);
PAINT MONO (-1910 2785);
FORCEPROP 0 LASTPIN (-1900 2825) $PN 177
J 2
(-1910 2835);
DISPLAY 0.680851 (-1910 2835);
PAINT MONO (-1910 2835);
FORCEPROP 0 LASTPIN (-1900 2875) $PN 180
J 2
(-1910 2885);
DISPLAY 0.680851 (-1910 2885);
PAINT MONO (-1910 2885);
FORCEPROP 0 LASTPIN (-1900 2925) $PN 182
J 2
(-1910 2935);
DISPLAY 0.680851 (-1910 2935);
PAINT MONO (-1910 2935);
FORCEPROP 0 LASTPIN (-1900 2975) $PN 184
J 2
(-1910 2985);
DISPLAY 0.680851 (-1910 2985);
PAINT MONO (-1910 2985);
FORCEPROP 0 LASTPIN (-1900 3025) $PN 186
J 2
(-1910 3035);
DISPLAY 0.680851 (-1910 3035);
PAINT MONO (-1910 3035);
FORCEPROP 0 LASTPIN (-1900 3075) $PN 188
J 2
(-1910 3085);
DISPLAY 0.680851 (-1910 3085);
PAINT MONO (-1910 3085);
FORCEPROP 0 LASTPIN (-1900 3125) $PN 191
J 2
(-1910 3135);
DISPLAY 0.680851 (-1910 3135);
PAINT MONO (-1910 3135);
FORCEPROP 0 LASTPIN (-1900 3175) $PN 193
J 2
(-1910 3185);
DISPLAY 0.680851 (-1910 3185);
PAINT MONO (-1910 3185);
FORCEPROP 0 LASTPIN (-1900 3225) $PN 195
J 2
(-1910 3235);
DISPLAY 0.680851 (-1910 3235);
PAINT MONO (-1910 3235);
FORCEPROP 0 LASTPIN (-1900 3275) $PN 197
J 2
(-1910 3285);
DISPLAY 0.680851 (-1910 3285);
PAINT MONO (-1910 3285);
FORCEPROP 0 LASTPIN (-1900 3325) $PN 199
J 2
(-1910 3335);
DISPLAY 0.680851 (-1910 3335);
PAINT MONO (-1910 3335);
FORCEPROP 0 LASTPIN (-1900 3375) $PN 202
J 2
(-1910 3385);
DISPLAY 0.680851 (-1910 3385);
PAINT MONO (-1910 3385);
FORCEPROP 0 LASTPIN (-1900 3425) $PN 204
J 2
(-1910 3435);
DISPLAY 0.680851 (-1910 3435);
PAINT MONO (-1910 3435);
FORCEPROP 0 LASTPIN (-1900 3475) $PN 206
J 2
(-1910 3485);
DISPLAY 0.680851 (-1910 3485);
PAINT MONO (-1910 3485);
FORCEPROP 0 LASTPIN (-1900 3525) $PN 208
J 2
(-1910 3535);
DISPLAY 0.680851 (-1910 3535);
PAINT MONO (-1910 3535);
FORCEPROP 0 LASTPIN (-1900 3575) $PN 210
J 2
(-1910 3585);
DISPLAY 0.680851 (-1910 3585);
PAINT MONO (-1910 3585);
FORCEPROP 0 LASTPIN (-1900 3625) $PN 212
J 2
(-1910 3635);
DISPLAY 0.680851 (-1910 3635);
PAINT MONO (-1910 3635);
FORCEPROP 0 LASTPIN (-1900 3675) $PN 214
J 2
(-1910 3685);
DISPLAY 0.680851 (-1910 3685);
PAINT MONO (-1910 3685);
FORCEPROP 0 LASTPIN (-1900 3725) $PN 216
J 2
(-1910 3735);
DISPLAY 0.680851 (-1910 3735);
PAINT MONO (-1910 3735);
FORCEPROP 0 LASTPIN (-1900 3775) $PN 219
J 2
(-1910 3785);
DISPLAY 0.680851 (-1910 3785);
PAINT MONO (-1910 3785);
FORCEPROP 0 LASTPIN (-1900 3825) $PN 222
J 2
(-1910 3835);
DISPLAY 0.680851 (-1910 3835);
PAINT MONO (-1910 3835);
FORCEPROP 0 LASTPIN (-1900 3875) $PN 224
J 2
(-1910 3885);
DISPLAY 0.680851 (-1910 3885);
PAINT MONO (-1910 3885);
FORCEPROP 0 LASTPIN (-1900 3925) $PN 226
J 2
(-1910 3935);
DISPLAY 0.680851 (-1910 3935);
PAINT MONO (-1910 3935);
FORCEPROP 0 LASTPIN (-1900 3975) $PN 228
J 2
(-1910 3985);
DISPLAY 0.680851 (-1910 3985);
PAINT MONO (-1910 3985);
FORCEPROP 0 LASTPIN (-1900 4025) $PN 230
J 2
(-1910 4035);
DISPLAY 0.680851 (-1910 4035);
PAINT MONO (-1910 4035);
FORCEPROP 0 LASTPIN (-1900 4075) $PN 233
J 2
(-1910 4085);
DISPLAY 0.680851 (-1910 4085);
PAINT MONO (-1910 4085);
FORCEPROP 0 LASTPIN (-1900 4125) $PN 235
J 2
(-1910 4135);
DISPLAY 0.680851 (-1910 4135);
PAINT MONO (-1910 4135);
FORCEPROP 0 LASTPIN (-1900 4175) $PN 237
J 2
(-1910 4185);
DISPLAY 0.680851 (-1910 4185);
PAINT MONO (-1910 4185);
FORCEPROP 0 LASTPIN (-1900 4225) $PN 240
J 2
(-1910 4235);
DISPLAY 0.680851 (-1910 4235);
PAINT MONO (-1910 4235);
FORCEPROP 0 LASTPIN (-1900 4275) $PN 242
J 2
(-1910 4285);
DISPLAY 0.680851 (-1910 4285);
PAINT MONO (-1910 4285);
FORCEPROP 0 LASTPIN (-1900 4325) $PN 244
J 2
(-1910 4335);
DISPLAY 0.680851 (-1910 4335);
PAINT MONO (-1910 4335);
FORCEPROP 0 LASTPIN (-1900 4375) $PN 246
J 2
(-1910 4385);
DISPLAY 0.680851 (-1910 4385);
PAINT MONO (-1910 4385);
FORCEPROP 0 LASTPIN (-1900 4425) $PN 248
J 2
(-1910 4435);
DISPLAY 0.680851 (-1910 4435);
PAINT MONO (-1910 4435);
FORCEPROP 0 LASTPIN (-1900 4475) $PN 251
J 2
(-1910 4485);
DISPLAY 0.680851 (-1910 4485);
PAINT MONO (-1910 4485);
FORCEPROP 0 LASTPIN (-1900 4525) $PN 253
J 2
(-1910 4535);
DISPLAY 0.680851 (-1910 4535);
PAINT MONO (-1910 4535);
FORCEPROP 0 LASTPIN (-1900 4575) $PN 255
J 2
(-1910 4585);
DISPLAY 0.680851 (-1910 4585);
PAINT MONO (-1910 4585);
FORCEPROP 0 LASTPIN (-1900 4625) $PN 257
J 2
(-1910 4635);
DISPLAY 0.680851 (-1910 4635);
PAINT MONO (-1910 4635);
FORCEPROP 0 LASTPIN (-1900 4675) $PN 259
J 2
(-1910 4685);
DISPLAY 0.680851 (-1910 4685);
PAINT MONO (-1910 4685);
FORCEPROP 0 LASTPIN (-1900 4725) $PN 262
J 2
(-1910 4735);
DISPLAY 0.680851 (-1910 4735);
PAINT MONO (-1910 4735);
FORCEPROP 0 LASTPIN (-1900 4775) $PN 264
J 2
(-1910 4785);
DISPLAY 0.680851 (-1910 4785);
PAINT MONO (-1910 4785);
FORCEPROP 0 LASTPIN (-1900 4825) $PN 266
J 2
(-1910 4835);
DISPLAY 0.680851 (-1910 4835);
PAINT MONO (-1910 4835);
FORCEPROP 0 LASTPIN (-1900 4875) $PN 268
J 2
(-1910 4885);
DISPLAY 0.680851 (-1910 4885);
PAINT MONO (-1910 4885);
FORCEPROP 0 LASTPIN (-1900 4925) $PN 270
J 2
(-1910 4935);
DISPLAY 0.680851 (-1910 4935);
PAINT MONO (-1910 4935);
FORCEPROP 0 LASTPIN (-1900 4975) $PN 273
J 2
(-1910 4985);
DISPLAY 0.680851 (-1910 4985);
PAINT MONO (-1910 4985);
FORCEPROP 0 LASTPIN (-1900 5025) $PN 275
J 2
(-1910 5035);
DISPLAY 0.680851 (-1910 5035);
PAINT MONO (-1910 5035);
FORCEPROP 0 LASTPIN (-1900 5075) $PN 277
J 2
(-1910 5085);
DISPLAY 0.680851 (-1910 5085);
PAINT MONO (-1910 5085);
FORCEPROP 0 LASTPIN (-1900 5125) $PN 279
J 2
(-1910 5135);
DISPLAY 0.680851 (-1910 5135);
PAINT MONO (-1910 5135);
FORCEPROP 0 LASTPIN (-1900 5175) $PN 281
J 2
(-1910 5185);
DISPLAY 0.680851 (-1910 5185);
PAINT MONO (-1910 5185);
FORCEPROP 0 LASTPIN (-1900 5225) $PN 284
J 2
(-1910 5235);
DISPLAY 0.680851 (-1910 5235);
PAINT MONO (-1910 5235);
FORCEPROP 0 LASTPIN (-1900 5275) $PN 286
J 2
(-1910 5285);
DISPLAY 0.680851 (-1910 5285);
PAINT MONO (-1910 5285);
FORCEPROP 0 LASTPIN (-1900 5325) $PN 288
J 2
(-1910 5335);
DISPLAY 0.680851 (-1910 5335);
PAINT MONO (-1910 5335);
FORCEPROP 2 LAST VALUE SCONN288_DDR506112002KQ
J 0
(-1750 5850);
DISPLAY 0.489362 (-1750 5850);
PAINT SKYBLUE (-1750 5850);
FORCEPROP 2 LAST PART_TYPE SMLF
J 0
(-1750 5900);
DISPLAY 1.021277 (-1750 5900);
FORCEPROP 1 LAST PART_NUMBER DFHST8FS479
J 0
(-1750 5725);
DISPLAY 0.468085 (-1750 5725);
PAINT SKYBLUE (-1750 5725);
FORCEPROP 1 LAST MATERIAL IO
J 0
(-1750 5650);
DISPLAY 0.468085 (-1750 5650);
PAINT SKYBLUE (-1750 5650);
FORCEPROP 1 LAST CDS_LMAN_SYM_OUTLINE -450,1800,450,-1750
J 0
(-1300 3825);
DISPLAY 0.468085 (-1300 3825);
PAINT GREEN (-1300 3825);
DISPLAY INVISIBLE (-1300 3825);
FORCEPROP 1 LAST PATH I177
J 0
(-1300 3825);
DISPLAY 0.723404 (-1300 3825);
PAINT GREEN (-1300 3825);
DISPLAY INVISIBLE (-1300 3825);
FORCEPROP 1 LAST NEEDS_NO_SIZE TRUE
J 0
(-1300 3825);
DISPLAY 0.723404 (-1300 3825);
PAINT GREEN (-1300 3825);
DISPLAY INVISIBLE (-1300 3825);
FORCEPROP 2 LAST CDS_LIB pure_quanta
J 0
(-1300 3825);
DISPLAY INVISIBLE (-1300 3825);
FORCEADD OFFPAGE..6
(-8050 2925);
FORCEPROP 2 LAST $XR5 136 
J 0
(-8899 2925);
DISPLAY 0.638298 (-8899 2925);
PAINT MONO (-8899 2925);
FORCEPROP 2 LAST $XR4 102 
J 0
(-8779 2925);
DISPLAY 0.638298 (-8779 2925);
PAINT MONO (-8779 2925);
FORCEPROP 2 LAST $XR3 101 
J 0
(-8659 2925);
DISPLAY 0.638298 (-8659 2925);
PAINT MONO (-8659 2925);
FORCEPROP 2 LAST $XR2 100 
J 0
(-8539 2925);
DISPLAY 0.638298 (-8539 2925);
PAINT MONO (-8539 2925);
FORCEPROP 2 LAST $XR1 99 
J 0
(-8419 2925);
DISPLAY 0.638298 (-8419 2925);
PAINT MONO (-8419 2925);
FORCEPROP 2 LAST $XR0 98 
J 0
(-8329 2925);
DISPLAY 0.638298 (-8329 2925);
PAINT MONO (-8329 2925);
FORCEPROP 2 LAST CDS_LIB mstr_standard
J 0
(-8050 2925);
DISPLAY 0.808511 (-8050 2925);
DISPLAY INVISIBLE (-8050 2925);
FORCEPROP 1 LAST OFFPAGE TRUE
J 0
(-7725 2800);
DISPLAY 0.872340 (-7725 2800);
PAINT GREEN (-7725 2800);
DISPLAY INVISIBLE (-7725 2800);
FORCEPROP 1 LAST COMMENT_BODY TRUE
J 0
(-7950 2850);
DISPLAY 0.872340 (-7950 2850);
PAINT GREEN (-7950 2850);
DISPLAY INVISIBLE (-7950 2850);
FORCEPROP 2 LAST PATH I179
J 0
(-8325 2975);
DISPLAY 1.021277 (-8325 2975);
DISPLAY INVISIBLE (-8325 2975);
FORCEADD OFFPAGE..1
(-8050 4525);
FORCEPROP 2 LAST $XR0 37 
J 0
(-8271 4525);
DISPLAY 0.638298 (-8271 4525);
PAINT MONO (-8271 4525);
FORCEPROP 2 LAST CDS_LIB mstr_standard
J 0
(-8050 4525);
DISPLAY 0.723404 (-8050 4525);
PAINT MONO (-8050 4525);
DISPLAY INVISIBLE (-8050 4525);
FORCEPROP 1 LAST OFFPAGE TRUE
J 0
(-7725 4400);
DISPLAY 0.872340 (-7725 4400);
PAINT GREEN (-7725 4400);
DISPLAY INVISIBLE (-7725 4400);
FORCEPROP 1 LAST COMMENT_BODY TRUE
J 0
(-7925 4425);
DISPLAY 0.872340 (-7925 4425);
PAINT GREEN (-7925 4425);
DISPLAY INVISIBLE (-7925 4425);
FORCEPROP 2 LAST PATH I18
J 0
(-8300 4575);
DISPLAY 1.021277 (-8300 4575);
DISPLAY INVISIBLE (-8300 4575);
FORCEADD Q_CAP..1
R 2
(-8600 3325);
FORCEPROP 1 LAST LOCATION C136
J 2
(-8650 3425);
DISPLAY 0.489362 (-8650 3425);
PAINT SKYBLUE (-8650 3425);
FORCEPROP 0 LAST $SEC 1
J 0
(-8650 3475);
DISPLAY 0.680851 (-8650 3475);
PAINT MONO (-8650 3475);
DISPLAY INVISIBLE (-8650 3475);
FORCEPROP 0 LAST CDS_SEC 1
J 0
(-8650 3475);
DISPLAY 1.021277 (-8650 3475);
DISPLAY INVISIBLE (-8650 3475);
FORCEPROP 1 LASTPIN (-8600 3425) $PN 1
J 2
(-8610 3405);
DISPLAY 0.489362 (-8610 3405);
PAINT MONO (-8610 3405);
FORCEPROP 1 LASTPIN (-8600 3225) $PN 2
J 2
(-8610 3205);
DISPLAY 0.489362 (-8610 3205);
PAINT MONO (-8610 3205);
FORCEPROP 1 LAST MATERIAL X7R
J 2
(-8650 3225);
DISPLAY 0.489362 (-8650 3225);
PAINT SKYBLUE (-8650 3225);
FORCEPROP 1 LAST TOLERANCE 10%
J 2
(-8650 3275);
DISPLAY 0.489362 (-8650 3275);
PAINT SKYBLUE (-8650 3275);
FORCEPROP 1 LAST VALUE 0.1UF
J 2
(-8650 3375);
DISPLAY 0.489362 (-8650 3375);
PAINT SKYBLUE (-8650 3375);
FORCEPROP 1 LAST VOLTAGE 25V
J 2
(-8650 3325);
DISPLAY 0.489362 (-8650 3325);
PAINT SKYBLUE (-8650 3325);
FORCEPROP 1 LAST PACK_TYPE 0402
J 2
(-8650 3125);
DISPLAY 0.489362 (-8650 3125);
PAINT SKYBLUE (-8650 3125);
FORCEPROP 1 LAST PART_NUMBER CH4104K1B00
J 2
(-8650 3175);
DISPLAY 0.489362 (-8650 3175);
PAINT SKYBLUE (-8650 3175);
FORCEPROP 2 LAST CDS_LIB pure_quanta
J 0
(-8600 3325);
DISPLAY INVISIBLE (-8600 3325);
FORCEPROP 0 LAST BOM_COST MEM
J 2
(-8655 3470);
DISPLAY 0.595745 (-8655 3470);
PAINT MONO (-8655 3470);
DISPLAY INVISIBLE (-8655 3470);
FORCEPROP 1 LAST PATH I185
J 2
(-8650 3475);
DISPLAY 0.978723 (-8650 3475);
PAINT WHITE (-8650 3475);
DISPLAY INVISIBLE (-8650 3475);
FORCEPROP 0 LAST ROOM MEM_CH_A_CPU0_DIMM1
J 2
(-8655 3470);
DISPLAY 0.595745 (-8655 3470);
PAINT RED (-8655 3470);
DISPLAY INVISIBLE (-8655 3470);
FORCEADD GND..1
(-8600 3100);
FORCEPROP 3 LASTPIN (-8600 3150) SIG_NAME GND\g
J 0
(-8590 3160);
DISPLAY 0.659574 (-8590 3160);
PAINT MONO (-8590 3160);
DISPLAY INVISIBLE (-8590 3160);
FORCEPROP 2 LAST CDS_LIB mstr_symbols
J 0
(-8600 3100);
DISPLAY 0.808511 (-8600 3100);
DISPLAY INVISIBLE (-8600 3100);
FORCEPROP 1 LAST SIZE 1B
J 0
(-8525 3050);
DISPLAY 0.723404 (-8525 3050);
PAINT GREEN (-8525 3050);
DISPLAY INVISIBLE (-8525 3050);
FORCEPROP 2 LAST BOM_COST MEM
J 0
(-8575 3225);
DISPLAY 0.659574 (-8575 3225);
DISPLAY INVISIBLE (-8575 3225);
FORCEPROP 1 LAST BODY_TYPE PLUMBING
J 0
(-8645 3057);
DISPLAY 0.276596 (-8645 3057);
PAINT GREEN (-8645 3057);
DISPLAY INVISIBLE (-8645 3057);
FORCEPROP 1 LAST PATH I186
J 0
(-8525 3100);
DISPLAY 0.872340 (-8525 3100);
PAINT AQUA (-8525 3100);
DISPLAY INVISIBLE (-8525 3100);
FORCEPROP 1 LAST VOLTAGE 0
J 0
(-8620 3195);
DISPLAY 0.829787 (-8620 3195);
PAINT SKYBLUE (-8620 3195);
DISPLAY INVISIBLE (-8620 3195);
FORCEPROP 2 LAST ROOM MEM_EFGH_DECOUPLING_CAPS
J 0
(-8575 3175);
DISPLAY 0.659574 (-8575 3175);
PAINT RED (-8575 3175);
DISPLAY INVISIBLE (-8575 3175);
FORCEPROP 1 LAST HDL_POWER GND
J 0
(-8600 3250);
DISPLAY 0.723404 (-8600 3250);
PAINT GREEN (-8600 3250);
DISPLAY INVISIBLE (-8600 3250);
FORCEADD OFFPAGE..6
(-8950 2225);
FORCEPROP 2 LAST $XR5 81 
J 0
(-9529 2225);
DISPLAY 0.638298 (-9529 2225);
PAINT MONO (-9529 2225);
FORCEPROP 2 LAST $XR4 102 
J 0
(-9439 2189);
DISPLAY 0.638298 (-9439 2189);
PAINT MONO (-9439 2189);
FORCEPROP 2 LAST $XR3 101 
J 0
(-9319 2189);
DISPLAY 0.638298 (-9319 2189);
PAINT MONO (-9319 2189);
FORCEPROP 2 LAST $XR2 100 
J 0
(-9439 2225);
DISPLAY 0.638298 (-9439 2225);
PAINT MONO (-9439 2225);
FORCEPROP 2 LAST $XR1 99 
J 0
(-9319 2225);
DISPLAY 0.638298 (-9319 2225);
PAINT MONO (-9319 2225);
FORCEPROP 2 LAST $XR0 98 
J 0
(-9229 2225);
DISPLAY 0.638298 (-9229 2225);
PAINT MONO (-9229 2225);
FORCEPROP 2 LAST CDS_LIB mstr_standard
J 0
(-8950 2225);
DISPLAY 0.808511 (-8950 2225);
DISPLAY INVISIBLE (-8950 2225);
FORCEPROP 1 LAST OFFPAGE TRUE
J 0
(-8625 2100);
DISPLAY 0.872340 (-8625 2100);
PAINT GREEN (-8625 2100);
DISPLAY INVISIBLE (-8625 2100);
FORCEPROP 1 LAST COMMENT_BODY TRUE
J 0
(-8850 2150);
DISPLAY 0.872340 (-8850 2150);
PAINT GREEN (-8850 2150);
DISPLAY INVISIBLE (-8850 2150);
FORCEPROP 2 LAST PATH I187
J 0
(-8900 2300);
DISPLAY 1.021277 (-8900 2300);
DISPLAY INVISIBLE (-8900 2300);
FORCEADD VCC_CORE..1
(-8525 2550);
FORCEPROP 3 LASTPIN (-8525 2500) SIG_NAME P3V3_STBY\g
J 0
(-8515 2510);
DISPLAY 0.659574 (-8515 2510);
PAINT MONO (-8515 2510);
DISPLAY INVISIBLE (-8515 2510);
FORCEPROP 1 LAST HDL_POWER P3V3_STBY
J 1
(-8525 2600);
DISPLAY 0.489362 (-8525 2600);
PAINT GREEN (-8525 2600);
FORCEPROP 2 LAST CDS_LIB mstr_symbols
J 0
(-8525 2550);
DISPLAY INVISIBLE (-8525 2550);
FORCEPROP 1 LAST PATH I188
J 0
(-8475 2575);
DISPLAY 0.872340 (-8475 2575);
PAINT AQUA (-8475 2575);
DISPLAY INVISIBLE (-8475 2575);
FORCEPROP 0 LAST VOLTAGE 3.3
J 0
(-8800 2700);
DISPLAY 1.021277 (-8800 2700);
PAINT SKYBLUE (-8800 2700);
DISPLAY INVISIBLE (-8800 2700);
FORCEPROP 2 LAST ROOM PVCCINFAON_CPU0_CTRL
J 0
(-8525 2650);
DISPLAY 0.808511 (-8525 2650);
PAINT RED (-8525 2650);
DISPLAY INVISIBLE (-8525 2650);
FORCEADD Q_RES..2
R 2
(-8525 2375);
FORCEPROP 1 LAST LOCATION R102
J 2
(-8570 2500);
DISPLAY 0.489362 (-8570 2500);
PAINT SKYBLUE (-8570 2500);
FORCEPROP 0 LAST $SEC 1
J 0
(-8550 2550);
DISPLAY 0.680851 (-8550 2550);
PAINT MONO (-8550 2550);
DISPLAY INVISIBLE (-8550 2550);
FORCEPROP 0 LAST CDS_SEC 1
J 0
(-8550 2550);
DISPLAY 1.021277 (-8550 2550);
DISPLAY INVISIBLE (-8550 2550);
FORCEPROP 1 LASTPIN (-8525 2475) $PN 1
J 2
(-8530 2437);
DISPLAY 0.489362 (-8530 2437);
PAINT MONO (-8530 2437);
FORCEPROP 1 LASTPIN (-8525 2275) $PN 2
J 2
(-8530 2285);
DISPLAY 0.489362 (-8530 2285);
PAINT MONO (-8530 2285);
FORCEPROP 1 LAST WATTAGE 1/16W
J 2
(-8575 2400);
DISPLAY 0.489362 (-8575 2400);
PAINT SKYBLUE (-8575 2400);
FORCEPROP 1 LAST MATERIAL CHIP
J 2
(-8575 2375);
DISPLAY 0.489362 (-8575 2375);
PAINT SKYBLUE (-8575 2375);
FORCEPROP 1 LAST TOLERANCE 5%
J 2
(-8575 2425);
DISPLAY 0.489362 (-8575 2425);
PAINT SKYBLUE (-8575 2425);
FORCEPROP 1 LAST VALUE 1K
J 2
(-8570 2450);
DISPLAY 0.489362 (-8570 2450);
PAINT SKYBLUE (-8570 2450);
FORCEPROP 1 LAST PART_NUMBER TMP_QCS21002JB34
J 2
(-8575 2350);
DISPLAY 0.489362 (-8575 2350);
PAINT SKYBLUE (-8575 2350);
FORCEPROP 1 LAST PACK_TYPE 0402LF
J 2
(-8575 2325);
DISPLAY 0.489362 (-8575 2325);
PAINT SKYBLUE (-8575 2325);
FORCEPROP 2 LAST BOM_COST MEM
J 2
(-8575 2550);
DISPLAY 0.808511 (-8575 2550);
DISPLAY INVISIBLE (-8575 2550);
FORCEPROP 2 LAST CDS_LIB pure_quanta
J 2
(-8525 2375);
DISPLAY INVISIBLE (-8525 2375);
FORCEPROP 1 LAST PATH I189
J 2
(-8575 2550);
DISPLAY 0.978723 (-8575 2550);
PAINT WHITE (-8575 2550);
DISPLAY INVISIBLE (-8575 2550);
FORCEPROP 2 LAST ROOM MEM_CH_A_CPU0_DIMM1
J 2
(-8575 2600);
DISPLAY 0.808511 (-8575 2600);
PAINT RED (-8575 2600);
DISPLAY INVISIBLE (-8575 2600);
FORCEADD OFFPAGE..1
(-8050 4675);
FORCEPROP 2 LAST $XR0 37 
J 0
(-8271 4675);
DISPLAY 0.638298 (-8271 4675);
PAINT MONO (-8271 4675);
FORCEPROP 2 LAST CDS_LIB mstr_standard
J 0
(-8050 4675);
DISPLAY 0.723404 (-8050 4675);
PAINT MONO (-8050 4675);
DISPLAY INVISIBLE (-8050 4675);
FORCEPROP 1 LAST OFFPAGE TRUE
J 0
(-7725 4550);
DISPLAY 0.872340 (-7725 4550);
PAINT GREEN (-7725 4550);
DISPLAY INVISIBLE (-7725 4550);
FORCEPROP 1 LAST COMMENT_BODY TRUE
J 0
(-7925 4575);
DISPLAY 0.872340 (-7925 4575);
PAINT GREEN (-7925 4575);
DISPLAY INVISIBLE (-7925 4575);
FORCEPROP 2 LAST PATH I19
J 0
(-8300 4725);
DISPLAY 1.021277 (-8300 4725);
DISPLAY INVISIBLE (-8300 4725);
FORCEADD Q_RES..1
R 2
(-8400 2225);
FORCEPROP 1 LAST LOCATION R303
J 2
(-8375 2250);
DISPLAY 0.489362 (-8375 2250);
PAINT SKYBLUE (-8375 2250);
FORCEPROP 0 LAST $SEC 1
J 0
(-8375 2300);
DISPLAY 0.680851 (-8375 2300);
PAINT MONO (-8375 2300);
DISPLAY INVISIBLE (-8375 2300);
FORCEPROP 0 LAST CDS_SEC 1
J 0
(-8375 2300);
DISPLAY 1.021277 (-8375 2300);
DISPLAY INVISIBLE (-8375 2300);
FORCEPROP 1 LASTPIN (-8300 2225) $PN 1
J 2
(-8312 2237);
DISPLAY 0.489362 (-8312 2237);
PAINT MONO (-8312 2237);
FORCEPROP 1 LASTPIN (-8500 2225) $PN 2
J 2
(-8462 2237);
DISPLAY 0.489362 (-8462 2237);
PAINT MONO (-8462 2237);
FORCEPROP 1 LAST VALUE 0
J 0
(-8400 2175);
DISPLAY 0.489362 (-8400 2175);
PAINT SKYBLUE (-8400 2175);
FORCEPROP 2 LAST CDS_LIB pure_quanta
J 0
(-8400 2225);
DISPLAY INVISIBLE (-8400 2225);
FORCEPROP 2 LAST BOM_COST MEM
J 0
(-8425 2375);
DISPLAY 0.744681 (-8425 2375);
PAINT WHITE (-8425 2375);
DISPLAY INVISIBLE (-8425 2375);
FORCEPROP 1 LAST PATH I190
J 2
(-8350 2375);
DISPLAY 0.978723 (-8350 2375);
PAINT WHITE (-8350 2375);
DISPLAY INVISIBLE (-8350 2375);
FORCEPROP 1 LAST WATTAGE 1/16W
J 0
(-8325 2150);
DISPLAY 0.489362 (-8325 2150);
PAINT SKYBLUE (-8325 2150);
DISPLAY INVISIBLE (-8325 2150);
FORCEPROP 1 LAST MATERIAL CHIP
J 0
(-8575 2200);
DISPLAY 0.489362 (-8575 2200);
PAINT SKYBLUE (-8575 2200);
DISPLAY INVISIBLE (-8575 2200);
FORCEPROP 1 LAST TOLERANCE 5%
J 2
(-8275 2200);
DISPLAY 0.489362 (-8275 2200);
PAINT SKYBLUE (-8275 2200);
DISPLAY INVISIBLE (-8275 2200);
FORCEPROP 1 LAST PART_NUMBER CS00002JB38
J 0
(-8500 2275);
DISPLAY 0.489362 (-8500 2275);
PAINT SKYBLUE (-8500 2275);
DISPLAY INVISIBLE (-8500 2275);
FORCEPROP 1 LAST PACK_TYPE 0402LF
J 0
(-8575 2150);
DISPLAY 0.489362 (-8575 2150);
PAINT SKYBLUE (-8575 2150);
DISPLAY INVISIBLE (-8575 2150);
FORCEPROP 2 LAST ROOM RST_CPU0_PLD_TO_DIMM
J 0
(-8425 2325);
DISPLAY 0.744681 (-8425 2325);
PAINT RED (-8425 2325);
DISPLAY INVISIBLE (-8425 2325);
FORCEADD Q_RES..2
(-8275 2375);
FORCEPROP 1 LAST LOCATION R103
J 0
(-8230 2500);
DISPLAY 0.489362 (-8230 2500);
PAINT SKYBLUE (-8230 2500);
FORCEPROP 0 LAST $SEC 1
J 0
(-8225 2550);
DISPLAY 0.680851 (-8225 2550);
PAINT MONO (-8225 2550);
DISPLAY INVISIBLE (-8225 2550);
FORCEPROP 0 LAST CDS_SEC 1
J 0
(-8225 2550);
DISPLAY 1.021277 (-8225 2550);
DISPLAY INVISIBLE (-8225 2550);
FORCEPROP 1 LASTPIN (-8275 2475) $PN 1
J 0
(-8270 2437);
DISPLAY 0.489362 (-8270 2437);
PAINT MONO (-8270 2437);
FORCEPROP 1 LASTPIN (-8275 2275) $PN 2
J 0
(-8270 2285);
DISPLAY 0.489362 (-8270 2285);
PAINT MONO (-8270 2285);
FORCEPROP 1 LAST TOLERANCE 5%
J 0
(-8225 2425);
DISPLAY 0.489362 (-8225 2425);
PAINT SKYBLUE (-8225 2425);
FORCEPROP 1 LAST VALUE 1K
J 0
(-8230 2450);
DISPLAY 0.489362 (-8230 2450);
PAINT SKYBLUE (-8230 2450);
FORCEPROP 1 LAST PACK_TYPE 0402LF
J 0
(-8225 2325);
DISPLAY 0.489362 (-8225 2325);
PAINT SKYBLUE (-8225 2325);
FORCEPROP 1 LAST MATERIAL EMPTY
J 0
(-8225 2375);
DISPLAY 0.489362 (-8225 2375);
PAINT RED (-8225 2375);
FORCEPROP 1 LAST WATTAGE 1/16W
J 0
(-8225 2400);
DISPLAY 0.489362 (-8225 2400);
PAINT SKYBLUE (-8225 2400);
FORCEPROP 2 LAST BOM_COST MEM
J 0
(-8225 2550);
DISPLAY 0.808511 (-8225 2550);
DISPLAY INVISIBLE (-8225 2550);
FORCEPROP 2 LAST CDS_LIB pure_quanta
J 2
(-8275 2375);
DISPLAY INVISIBLE (-8275 2375);
FORCEPROP 1 LAST PATH I191
J 0
(-8225 2550);
DISPLAY 0.978723 (-8225 2550);
PAINT WHITE (-8225 2550);
DISPLAY INVISIBLE (-8225 2550);
FORCEPROP 1 LAST PART_NUMBER TMP_QCS21002JB34
J 0
(-8225 2350);
DISPLAY 0.489362 (-8225 2350);
PAINT SKYBLUE (-8225 2350);
DISPLAY INVISIBLE (-8225 2350);
FORCEPROP 2 LAST ROOM MEM_CH_A_CPU0_DIMM1
J 0
(-8225 2600);
DISPLAY 0.808511 (-8225 2600);
PAINT RED (-8225 2600);
DISPLAY INVISIBLE (-8225 2600);
FORCEADD VCC_CORE..1
(-8275 2550);
FORCEPROP 3 LASTPIN (-8275 2500) SIG_NAME P3V3_STBY\g
J 0
(-8265 2510);
DISPLAY 0.659574 (-8265 2510);
PAINT MONO (-8265 2510);
DISPLAY INVISIBLE (-8265 2510);
FORCEPROP 1 LAST HDL_POWER P3V3_STBY
J 1
(-8275 2600);
DISPLAY 0.489362 (-8275 2600);
PAINT GREEN (-8275 2600);
FORCEPROP 2 LAST CDS_LIB mstr_symbols
J 0
(-8275 2550);
DISPLAY INVISIBLE (-8275 2550);
FORCEPROP 1 LAST PATH I192
J 0
(-8225 2575);
DISPLAY 0.872340 (-8225 2575);
PAINT AQUA (-8225 2575);
DISPLAY INVISIBLE (-8225 2575);
FORCEPROP 0 LAST VOLTAGE 3.3
J 0
(-8550 2700);
DISPLAY 1.021277 (-8550 2700);
PAINT SKYBLUE (-8550 2700);
DISPLAY INVISIBLE (-8550 2700);
FORCEPROP 2 LAST ROOM PVCCINFAON_CPU0_CTRL
J 0
(-8275 2650);
DISPLAY 0.808511 (-8275 2650);
PAINT RED (-8275 2650);
DISPLAY INVISIBLE (-8275 2650);
FORCEADD OFFPAGE..2
(-2425 4650);
FORCEPROP 2 LAST $XR0 37 
J 0
(-2236 4650);
DISPLAY 0.638298 (-2236 4650);
PAINT MONO (-2236 4650);
FORCEPROP 2 LAST CDS_LIB mstr_standard
J 0
(-2425 4650);
DISPLAY 0.723404 (-2425 4650);
PAINT MONO (-2425 4650);
DISPLAY INVISIBLE (-2425 4650);
FORCEPROP 1 LAST OFFPAGE TRUE
J 0
(-2100 4525);
DISPLAY 0.723404 (-2100 4525);
PAINT GREEN (-2100 4525);
DISPLAY INVISIBLE (-2100 4525);
FORCEPROP 1 LAST COMMENT_BODY TRUE
J 0
(-2470 4555);
DISPLAY 0.872340 (-2470 4555);
PAINT GREEN (-2470 4555);
DISPLAY INVISIBLE (-2470 4555);
FORCEPROP 2 LAST PATH I194
J 0
(-2225 4700);
DISPLAY 0.680851 (-2225 4700);
DISPLAY INVISIBLE (-2225 4700);
FORCEADD OFFPAGE..2
(-2425 4600);
FORCEPROP 2 LAST $XR0 37 
J 0
(-2236 4600);
DISPLAY 0.638298 (-2236 4600);
PAINT MONO (-2236 4600);
FORCEPROP 2 LAST CDS_LIB mstr_standard
J 0
(-2425 4600);
DISPLAY 0.723404 (-2425 4600);
PAINT MONO (-2425 4600);
DISPLAY INVISIBLE (-2425 4600);
FORCEPROP 1 LAST OFFPAGE TRUE
J 0
(-2100 4475);
DISPLAY 0.723404 (-2100 4475);
PAINT GREEN (-2100 4475);
DISPLAY INVISIBLE (-2100 4475);
FORCEPROP 1 LAST COMMENT_BODY TRUE
J 0
(-2470 4505);
DISPLAY 0.872340 (-2470 4505);
PAINT GREEN (-2470 4505);
DISPLAY INVISIBLE (-2470 4505);
FORCEPROP 2 LAST PATH I195
J 0
(-2225 4650);
DISPLAY 0.680851 (-2225 4650);
DISPLAY INVISIBLE (-2225 4650);
FORCEADD OFFPAGE..2
(-2425 3600);
FORCEPROP 2 LAST $XR0 37 
J 0
(-2236 3600);
DISPLAY 0.638298 (-2236 3600);
PAINT MONO (-2236 3600);
FORCEPROP 2 LAST CDS_LIB mstr_standard
J 0
(-2425 3600);
DISPLAY 0.723404 (-2425 3600);
PAINT MONO (-2425 3600);
DISPLAY INVISIBLE (-2425 3600);
FORCEPROP 1 LAST OFFPAGE TRUE
J 0
(-2100 3475);
DISPLAY 0.723404 (-2100 3475);
PAINT GREEN (-2100 3475);
DISPLAY INVISIBLE (-2100 3475);
FORCEPROP 1 LAST COMMENT_BODY TRUE
J 0
(-2470 3505);
DISPLAY 0.872340 (-2470 3505);
PAINT GREEN (-2470 3505);
DISPLAY INVISIBLE (-2470 3505);
FORCEPROP 2 LAST PATH I196
J 0
(-2225 3650);
DISPLAY 0.680851 (-2225 3650);
DISPLAY INVISIBLE (-2225 3650);
FORCEADD OFFPAGE..2
(-2425 3550);
FORCEPROP 2 LAST $XR0 37 
J 0
(-2236 3550);
DISPLAY 0.638298 (-2236 3550);
PAINT MONO (-2236 3550);
FORCEPROP 2 LAST CDS_LIB mstr_standard
J 0
(-2425 3550);
DISPLAY 0.723404 (-2425 3550);
PAINT MONO (-2425 3550);
DISPLAY INVISIBLE (-2425 3550);
FORCEPROP 1 LAST OFFPAGE TRUE
J 0
(-2100 3425);
DISPLAY 0.723404 (-2100 3425);
PAINT GREEN (-2100 3425);
DISPLAY INVISIBLE (-2100 3425);
FORCEPROP 1 LAST COMMENT_BODY TRUE
J 0
(-2470 3455);
DISPLAY 0.872340 (-2470 3455);
PAINT GREEN (-2470 3455);
DISPLAY INVISIBLE (-2470 3455);
FORCEPROP 2 LAST PATH I197
J 0
(-2225 3600);
DISPLAY 0.680851 (-2225 3600);
DISPLAY INVISIBLE (-2225 3600);
FORCEADD TAP..1
(-3025 4550);
FORCEPROP 3 LASTPIN (-3075 4550) SIG_NAME M_A_CPU1_SA_DQS_DN<9>
J 0
(-3065 4560);
DISPLAY 0.659574 (-3065 4560);
PAINT MONO (-3065 4560);
DISPLAY INVISIBLE (-3065 4560);
FORCEPROP 1 LASTPIN (-3075 4550) BN 9
J 0
(-3087 4558);
DISPLAY 0.489362 (-3087 4558);
PAINT GREEN (-3087 4558);
FORCEPROP 2 LAST CDS_LIB mstr_standard
J 0
(-3025 4550);
DISPLAY 0.723404 (-3025 4550);
PAINT MONO (-3025 4550);
DISPLAY INVISIBLE (-3025 4550);
FORCEPROP 1 LAST BODY_TYPE PLUMBING
J 0
(-3025 4600);
DISPLAY 0.872340 (-3025 4600);
PAINT GREEN (-3025 4600);
DISPLAY INVISIBLE (-3025 4600);
FORCEPROP 1 LAST HDL_TAP TRUE
J 0
(-2700 4425);
DISPLAY 0.872340 (-2700 4425);
DISPLAY INVISIBLE (-2700 4425);
FORCEPROP 1 LAST PATH I198
J 0
(-3027 4550);
DISPLAY 0.872340 (-3027 4550);
PAINT GREEN (-3027 4550);
DISPLAY INVISIBLE (-3027 4550);
FORCEADD TAP..1
(-3025 4450);
FORCEPROP 3 LASTPIN (-3075 4450) SIG_NAME M_A_CPU1_SA_DQS_DN<8>
J 0
(-3065 4460);
DISPLAY 0.659574 (-3065 4460);
PAINT MONO (-3065 4460);
DISPLAY INVISIBLE (-3065 4460);
FORCEPROP 1 LASTPIN (-3075 4450) BN 8
J 0
(-3087 4458);
DISPLAY 0.489362 (-3087 4458);
PAINT GREEN (-3087 4458);
FORCEPROP 2 LAST CDS_LIB mstr_standard
J 0
(-3025 4450);
DISPLAY 0.723404 (-3025 4450);
PAINT MONO (-3025 4450);
DISPLAY INVISIBLE (-3025 4450);
FORCEPROP 1 LAST BODY_TYPE PLUMBING
J 0
(-3025 4500);
DISPLAY 0.872340 (-3025 4500);
PAINT GREEN (-3025 4500);
DISPLAY INVISIBLE (-3025 4500);
FORCEPROP 1 LAST HDL_TAP TRUE
J 0
(-2700 4325);
DISPLAY 0.872340 (-2700 4325);
DISPLAY INVISIBLE (-2700 4325);
FORCEPROP 1 LAST PATH I199
J 0
(-3027 4450);
DISPLAY 0.872340 (-3027 4450);
PAINT GREEN (-3027 4450);
DISPLAY INVISIBLE (-3027 4450);
FORCEADD OFFPAGE..5
(-8050 2075);
FORCEPROP 2 LAST $XR0 37 
J 0
(-8304 2075);
DISPLAY 0.638298 (-8304 2075);
PAINT MONO (-8304 2075);
FORCEPROP 2 LAST CDS_LIB mstr_standard
J 0
(-8050 2075);
DISPLAY 0.808511 (-8050 2075);
DISPLAY INVISIBLE (-8050 2075);
FORCEPROP 1 LAST OFFPAGE TRUE
J 0
(-7725 1950);
DISPLAY 0.872340 (-7725 1950);
PAINT GREEN (-7725 1950);
DISPLAY INVISIBLE (-7725 1950);
FORCEPROP 1 LAST COMMENT_BODY TRUE
J 0
(-7950 2000);
DISPLAY 0.872340 (-7950 2000);
PAINT GREEN (-7950 2000);
DISPLAY INVISIBLE (-7950 2000);
FORCEPROP 2 LAST PATH I2
J 0
(-8250 2125);
DISPLAY 1.021277 (-8250 2125);
DISPLAY INVISIBLE (-8250 2125);
FORCEADD OFFPAGE..1
(-8050 5125);
FORCEPROP 2 LAST $XR0 37 
J 0
(-8271 5125);
DISPLAY 0.638298 (-8271 5125);
PAINT MONO (-8271 5125);
FORCEPROP 2 LAST CDS_LIB mstr_standard
J 0
(-8050 5125);
DISPLAY 0.723404 (-8050 5125);
PAINT MONO (-8050 5125);
DISPLAY INVISIBLE (-8050 5125);
FORCEPROP 1 LAST OFFPAGE TRUE
J 0
(-7725 5000);
DISPLAY 0.872340 (-7725 5000);
PAINT GREEN (-7725 5000);
DISPLAY INVISIBLE (-7725 5000);
FORCEPROP 1 LAST COMMENT_BODY TRUE
J 0
(-7925 5025);
DISPLAY 0.872340 (-7925 5025);
PAINT GREEN (-7925 5025);
DISPLAY INVISIBLE (-7925 5025);
FORCEPROP 2 LAST PATH I20
J 0
(-8300 5175);
DISPLAY 1.021277 (-8300 5175);
DISPLAY INVISIBLE (-8300 5175);
FORCEADD TAP..1
(-3025 4350);
FORCEPROP 3 LASTPIN (-3075 4350) SIG_NAME M_A_CPU1_SA_DQS_DN<7>
J 0
(-3065 4360);
DISPLAY 0.659574 (-3065 4360);
PAINT MONO (-3065 4360);
DISPLAY INVISIBLE (-3065 4360);
FORCEPROP 1 LASTPIN (-3075 4350) BN 7
J 0
(-3087 4358);
DISPLAY 0.489362 (-3087 4358);
PAINT GREEN (-3087 4358);
FORCEPROP 2 LAST CDS_LIB mstr_standard
J 0
(-3025 4350);
DISPLAY 0.723404 (-3025 4350);
PAINT MONO (-3025 4350);
DISPLAY INVISIBLE (-3025 4350);
FORCEPROP 1 LAST BODY_TYPE PLUMBING
J 0
(-3025 4400);
DISPLAY 0.872340 (-3025 4400);
PAINT GREEN (-3025 4400);
DISPLAY INVISIBLE (-3025 4400);
FORCEPROP 1 LAST HDL_TAP TRUE
J 0
(-2700 4225);
DISPLAY 0.872340 (-2700 4225);
DISPLAY INVISIBLE (-2700 4225);
FORCEPROP 1 LAST PATH I200
J 0
(-3027 4350);
DISPLAY 0.872340 (-3027 4350);
PAINT GREEN (-3027 4350);
DISPLAY INVISIBLE (-3027 4350);
FORCEADD TAP..1
(-3225 4600);
FORCEPROP 3 LASTPIN (-3275 4600) SIG_NAME M_A_CPU1_SA_DQS_DP<9>
J 0
(-3265 4610);
DISPLAY 0.659574 (-3265 4610);
PAINT MONO (-3265 4610);
DISPLAY INVISIBLE (-3265 4610);
FORCEPROP 1 LASTPIN (-3275 4600) BN 9
J 0
(-3287 4608);
DISPLAY 0.489362 (-3287 4608);
PAINT GREEN (-3287 4608);
FORCEPROP 2 LAST CDS_LIB mstr_standard
J 0
(-3225 4600);
DISPLAY 0.723404 (-3225 4600);
PAINT MONO (-3225 4600);
DISPLAY INVISIBLE (-3225 4600);
FORCEPROP 1 LAST BODY_TYPE PLUMBING
J 0
(-3225 4650);
DISPLAY 0.872340 (-3225 4650);
PAINT GREEN (-3225 4650);
DISPLAY INVISIBLE (-3225 4650);
FORCEPROP 1 LAST HDL_TAP TRUE
J 0
(-2900 4475);
DISPLAY 0.872340 (-2900 4475);
DISPLAY INVISIBLE (-2900 4475);
FORCEPROP 1 LAST PATH I201
J 0
(-3227 4600);
DISPLAY 0.872340 (-3227 4600);
PAINT GREEN (-3227 4600);
DISPLAY INVISIBLE (-3227 4600);
FORCEADD TAP..1
(-3225 4500);
FORCEPROP 3 LASTPIN (-3275 4500) SIG_NAME M_A_CPU1_SA_DQS_DP<8>
J 0
(-3265 4510);
DISPLAY 0.659574 (-3265 4510);
PAINT MONO (-3265 4510);
DISPLAY INVISIBLE (-3265 4510);
FORCEPROP 1 LASTPIN (-3275 4500) BN 8
J 0
(-3287 4508);
DISPLAY 0.489362 (-3287 4508);
PAINT GREEN (-3287 4508);
FORCEPROP 2 LAST CDS_LIB mstr_standard
J 0
(-3225 4500);
DISPLAY 0.723404 (-3225 4500);
PAINT MONO (-3225 4500);
DISPLAY INVISIBLE (-3225 4500);
FORCEPROP 1 LAST BODY_TYPE PLUMBING
J 0
(-3225 4550);
DISPLAY 0.872340 (-3225 4550);
PAINT GREEN (-3225 4550);
DISPLAY INVISIBLE (-3225 4550);
FORCEPROP 1 LAST HDL_TAP TRUE
J 0
(-2900 4375);
DISPLAY 0.872340 (-2900 4375);
DISPLAY INVISIBLE (-2900 4375);
FORCEPROP 1 LAST PATH I202
J 0
(-3227 4500);
DISPLAY 0.872340 (-3227 4500);
PAINT GREEN (-3227 4500);
DISPLAY INVISIBLE (-3227 4500);
FORCEADD TAP..1
(-3225 4400);
FORCEPROP 3 LASTPIN (-3275 4400) SIG_NAME M_A_CPU1_SA_DQS_DP<7>
J 0
(-3265 4410);
DISPLAY 0.659574 (-3265 4410);
PAINT MONO (-3265 4410);
DISPLAY INVISIBLE (-3265 4410);
FORCEPROP 1 LASTPIN (-3275 4400) BN 7
J 0
(-3287 4408);
DISPLAY 0.489362 (-3287 4408);
PAINT GREEN (-3287 4408);
FORCEPROP 2 LAST CDS_LIB mstr_standard
J 0
(-3225 4400);
DISPLAY 0.723404 (-3225 4400);
PAINT MONO (-3225 4400);
DISPLAY INVISIBLE (-3225 4400);
FORCEPROP 1 LAST BODY_TYPE PLUMBING
J 0
(-3225 4450);
DISPLAY 0.872340 (-3225 4450);
PAINT GREEN (-3225 4450);
DISPLAY INVISIBLE (-3225 4450);
FORCEPROP 1 LAST HDL_TAP TRUE
J 0
(-2900 4275);
DISPLAY 0.872340 (-2900 4275);
DISPLAY INVISIBLE (-2900 4275);
FORCEPROP 1 LAST PATH I203
J 0
(-3227 4400);
DISPLAY 0.872340 (-3227 4400);
PAINT GREEN (-3227 4400);
DISPLAY INVISIBLE (-3227 4400);
FORCEADD TAP..1
(-3025 4250);
FORCEPROP 3 LASTPIN (-3075 4250) SIG_NAME M_A_CPU1_SA_DQS_DN<6>
J 0
(-3065 4260);
DISPLAY 0.659574 (-3065 4260);
PAINT MONO (-3065 4260);
DISPLAY INVISIBLE (-3065 4260);
FORCEPROP 1 LASTPIN (-3075 4250) BN 6
J 0
(-3087 4258);
DISPLAY 0.489362 (-3087 4258);
PAINT GREEN (-3087 4258);
FORCEPROP 2 LAST CDS_LIB mstr_standard
J 0
(-3025 4250);
DISPLAY 0.723404 (-3025 4250);
PAINT MONO (-3025 4250);
DISPLAY INVISIBLE (-3025 4250);
FORCEPROP 1 LAST BODY_TYPE PLUMBING
J 0
(-3025 4300);
DISPLAY 0.872340 (-3025 4300);
PAINT GREEN (-3025 4300);
DISPLAY INVISIBLE (-3025 4300);
FORCEPROP 1 LAST HDL_TAP TRUE
J 0
(-2700 4125);
DISPLAY 0.872340 (-2700 4125);
DISPLAY INVISIBLE (-2700 4125);
FORCEPROP 1 LAST PATH I204
J 0
(-3027 4250);
DISPLAY 0.872340 (-3027 4250);
PAINT GREEN (-3027 4250);
DISPLAY INVISIBLE (-3027 4250);
FORCEADD TAP..1
(-3025 4150);
FORCEPROP 3 LASTPIN (-3075 4150) SIG_NAME M_A_CPU1_SA_DQS_DN<5>
J 0
(-3065 4160);
DISPLAY 0.659574 (-3065 4160);
PAINT MONO (-3065 4160);
DISPLAY INVISIBLE (-3065 4160);
FORCEPROP 1 LASTPIN (-3075 4150) BN 5
J 0
(-3087 4158);
DISPLAY 0.489362 (-3087 4158);
PAINT GREEN (-3087 4158);
FORCEPROP 2 LAST CDS_LIB mstr_standard
J 0
(-3025 4150);
DISPLAY 0.723404 (-3025 4150);
PAINT MONO (-3025 4150);
DISPLAY INVISIBLE (-3025 4150);
FORCEPROP 1 LAST BODY_TYPE PLUMBING
J 0
(-3025 4200);
DISPLAY 0.872340 (-3025 4200);
PAINT GREEN (-3025 4200);
DISPLAY INVISIBLE (-3025 4200);
FORCEPROP 1 LAST HDL_TAP TRUE
J 0
(-2700 4025);
DISPLAY 0.872340 (-2700 4025);
DISPLAY INVISIBLE (-2700 4025);
FORCEPROP 1 LAST PATH I205
J 0
(-3027 4150);
DISPLAY 0.872340 (-3027 4150);
PAINT GREEN (-3027 4150);
DISPLAY INVISIBLE (-3027 4150);
FORCEADD TAP..1
(-3025 3950);
FORCEPROP 3 LASTPIN (-3075 3950) SIG_NAME M_A_CPU1_SA_DQS_DN<3>
J 0
(-3065 3960);
DISPLAY 0.659574 (-3065 3960);
PAINT MONO (-3065 3960);
DISPLAY INVISIBLE (-3065 3960);
FORCEPROP 1 LASTPIN (-3075 3950) BN 3
J 0
(-3087 3958);
DISPLAY 0.489362 (-3087 3958);
PAINT GREEN (-3087 3958);
FORCEPROP 2 LAST CDS_LIB mstr_standard
J 0
(-3025 3950);
DISPLAY 0.723404 (-3025 3950);
PAINT MONO (-3025 3950);
DISPLAY INVISIBLE (-3025 3950);
FORCEPROP 1 LAST BODY_TYPE PLUMBING
J 0
(-3025 4000);
DISPLAY 0.872340 (-3025 4000);
PAINT GREEN (-3025 4000);
DISPLAY INVISIBLE (-3025 4000);
FORCEPROP 1 LAST HDL_TAP TRUE
J 0
(-2700 3825);
DISPLAY 0.872340 (-2700 3825);
DISPLAY INVISIBLE (-2700 3825);
FORCEPROP 1 LAST PATH I206
J 0
(-3027 3950);
DISPLAY 0.872340 (-3027 3950);
PAINT GREEN (-3027 3950);
DISPLAY INVISIBLE (-3027 3950);
FORCEADD TAP..1
(-3025 4050);
FORCEPROP 3 LASTPIN (-3075 4050) SIG_NAME M_A_CPU1_SA_DQS_DN<4>
J 0
(-3065 4060);
DISPLAY 0.659574 (-3065 4060);
PAINT MONO (-3065 4060);
DISPLAY INVISIBLE (-3065 4060);
FORCEPROP 1 LASTPIN (-3075 4050) BN 4
J 0
(-3087 4058);
DISPLAY 0.489362 (-3087 4058);
PAINT GREEN (-3087 4058);
FORCEPROP 2 LAST CDS_LIB mstr_standard
J 0
(-3025 4050);
DISPLAY 0.723404 (-3025 4050);
PAINT MONO (-3025 4050);
DISPLAY INVISIBLE (-3025 4050);
FORCEPROP 1 LAST BODY_TYPE PLUMBING
J 0
(-3025 4100);
DISPLAY 0.872340 (-3025 4100);
PAINT GREEN (-3025 4100);
DISPLAY INVISIBLE (-3025 4100);
FORCEPROP 1 LAST HDL_TAP TRUE
J 0
(-2700 3925);
DISPLAY 0.872340 (-2700 3925);
DISPLAY INVISIBLE (-2700 3925);
FORCEPROP 1 LAST PATH I207
J 0
(-3027 4050);
DISPLAY 0.872340 (-3027 4050);
PAINT GREEN (-3027 4050);
DISPLAY INVISIBLE (-3027 4050);
FORCEADD TAP..1
(-3025 3850);
FORCEPROP 3 LASTPIN (-3075 3850) SIG_NAME M_A_CPU1_SA_DQS_DN<2>
J 0
(-3065 3860);
DISPLAY 0.659574 (-3065 3860);
PAINT MONO (-3065 3860);
DISPLAY INVISIBLE (-3065 3860);
FORCEPROP 1 LASTPIN (-3075 3850) BN 2
J 0
(-3087 3858);
DISPLAY 0.489362 (-3087 3858);
PAINT GREEN (-3087 3858);
FORCEPROP 2 LAST CDS_LIB mstr_standard
J 0
(-3025 3850);
DISPLAY 0.723404 (-3025 3850);
PAINT MONO (-3025 3850);
DISPLAY INVISIBLE (-3025 3850);
FORCEPROP 1 LAST BODY_TYPE PLUMBING
J 0
(-3025 3900);
DISPLAY 0.872340 (-3025 3900);
PAINT GREEN (-3025 3900);
DISPLAY INVISIBLE (-3025 3900);
FORCEPROP 1 LAST HDL_TAP TRUE
J 0
(-2700 3725);
DISPLAY 0.872340 (-2700 3725);
DISPLAY INVISIBLE (-2700 3725);
FORCEPROP 1 LAST PATH I208
J 0
(-3027 3850);
DISPLAY 0.872340 (-3027 3850);
PAINT GREEN (-3027 3850);
DISPLAY INVISIBLE (-3027 3850);
FORCEADD TAP..1
(-3225 4100);
FORCEPROP 3 LASTPIN (-3275 4100) SIG_NAME M_A_CPU1_SA_DQS_DP<4>
J 0
(-3265 4110);
DISPLAY 0.659574 (-3265 4110);
PAINT MONO (-3265 4110);
DISPLAY INVISIBLE (-3265 4110);
FORCEPROP 1 LASTPIN (-3275 4100) BN 4
J 0
(-3287 4108);
DISPLAY 0.489362 (-3287 4108);
PAINT GREEN (-3287 4108);
FORCEPROP 2 LAST CDS_LIB mstr_standard
J 0
(-3225 4100);
DISPLAY 0.723404 (-3225 4100);
PAINT MONO (-3225 4100);
DISPLAY INVISIBLE (-3225 4100);
FORCEPROP 1 LAST BODY_TYPE PLUMBING
J 0
(-3225 4150);
DISPLAY 0.872340 (-3225 4150);
PAINT GREEN (-3225 4150);
DISPLAY INVISIBLE (-3225 4150);
FORCEPROP 1 LAST HDL_TAP TRUE
J 0
(-2900 3975);
DISPLAY 0.872340 (-2900 3975);
DISPLAY INVISIBLE (-2900 3975);
FORCEPROP 1 LAST PATH I209
J 0
(-3227 4100);
DISPLAY 0.872340 (-3227 4100);
PAINT GREEN (-3227 4100);
DISPLAY INVISIBLE (-3227 4100);
FORCEADD OFFPAGE..1
(-8050 5525);
FORCEPROP 2 LAST $XR0 37 
J 0
(-8271 5525);
DISPLAY 0.638298 (-8271 5525);
PAINT MONO (-8271 5525);
FORCEPROP 2 LAST CDS_LIB mstr_standard
J 0
(-8050 5525);
DISPLAY 0.723404 (-8050 5525);
PAINT MONO (-8050 5525);
DISPLAY INVISIBLE (-8050 5525);
FORCEPROP 1 LAST OFFPAGE TRUE
J 0
(-7725 5400);
DISPLAY 0.872340 (-7725 5400);
PAINT GREEN (-7725 5400);
DISPLAY INVISIBLE (-7725 5400);
FORCEPROP 1 LAST COMMENT_BODY TRUE
J 0
(-7925 5425);
DISPLAY 0.872340 (-7925 5425);
PAINT GREEN (-7925 5425);
DISPLAY INVISIBLE (-7925 5425);
FORCEPROP 2 LAST PATH I21
J 0
(-8300 5575);
DISPLAY 1.021277 (-8300 5575);
DISPLAY INVISIBLE (-8300 5575);
FORCEADD TAP..1
(-3225 4200);
FORCEPROP 3 LASTPIN (-3275 4200) SIG_NAME M_A_CPU1_SA_DQS_DP<5>
J 0
(-3265 4210);
DISPLAY 0.659574 (-3265 4210);
PAINT MONO (-3265 4210);
DISPLAY INVISIBLE (-3265 4210);
FORCEPROP 1 LASTPIN (-3275 4200) BN 5
J 0
(-3287 4208);
DISPLAY 0.489362 (-3287 4208);
PAINT GREEN (-3287 4208);
FORCEPROP 2 LAST CDS_LIB mstr_standard
J 0
(-3225 4200);
DISPLAY 0.723404 (-3225 4200);
PAINT MONO (-3225 4200);
DISPLAY INVISIBLE (-3225 4200);
FORCEPROP 1 LAST BODY_TYPE PLUMBING
J 0
(-3225 4250);
DISPLAY 0.872340 (-3225 4250);
PAINT GREEN (-3225 4250);
DISPLAY INVISIBLE (-3225 4250);
FORCEPROP 1 LAST HDL_TAP TRUE
J 0
(-2900 4075);
DISPLAY 0.872340 (-2900 4075);
DISPLAY INVISIBLE (-2900 4075);
FORCEPROP 1 LAST PATH I210
J 0
(-3227 4200);
DISPLAY 0.872340 (-3227 4200);
PAINT GREEN (-3227 4200);
DISPLAY INVISIBLE (-3227 4200);
FORCEADD TAP..1
(-3225 4300);
FORCEPROP 3 LASTPIN (-3275 4300) SIG_NAME M_A_CPU1_SA_DQS_DP<6>
J 0
(-3265 4310);
DISPLAY 0.659574 (-3265 4310);
PAINT MONO (-3265 4310);
DISPLAY INVISIBLE (-3265 4310);
FORCEPROP 1 LASTPIN (-3275 4300) BN 6
J 0
(-3287 4308);
DISPLAY 0.489362 (-3287 4308);
PAINT GREEN (-3287 4308);
FORCEPROP 2 LAST CDS_LIB mstr_standard
J 0
(-3225 4300);
DISPLAY 0.723404 (-3225 4300);
PAINT MONO (-3225 4300);
DISPLAY INVISIBLE (-3225 4300);
FORCEPROP 1 LAST BODY_TYPE PLUMBING
J 0
(-3225 4350);
DISPLAY 0.872340 (-3225 4350);
PAINT GREEN (-3225 4350);
DISPLAY INVISIBLE (-3225 4350);
FORCEPROP 1 LAST HDL_TAP TRUE
J 0
(-2900 4175);
DISPLAY 0.872340 (-2900 4175);
DISPLAY INVISIBLE (-2900 4175);
FORCEPROP 1 LAST PATH I211
J 0
(-3227 4300);
DISPLAY 0.872340 (-3227 4300);
PAINT GREEN (-3227 4300);
DISPLAY INVISIBLE (-3227 4300);
FORCEADD TAP..1
(-3225 4000);
FORCEPROP 3 LASTPIN (-3275 4000) SIG_NAME M_A_CPU1_SA_DQS_DP<3>
J 0
(-3265 4010);
DISPLAY 0.659574 (-3265 4010);
PAINT MONO (-3265 4010);
DISPLAY INVISIBLE (-3265 4010);
FORCEPROP 1 LASTPIN (-3275 4000) BN 3
J 0
(-3287 4008);
DISPLAY 0.489362 (-3287 4008);
PAINT GREEN (-3287 4008);
FORCEPROP 2 LAST CDS_LIB mstr_standard
J 0
(-3225 4000);
DISPLAY 0.723404 (-3225 4000);
PAINT MONO (-3225 4000);
DISPLAY INVISIBLE (-3225 4000);
FORCEPROP 1 LAST BODY_TYPE PLUMBING
J 0
(-3225 4050);
DISPLAY 0.872340 (-3225 4050);
PAINT GREEN (-3225 4050);
DISPLAY INVISIBLE (-3225 4050);
FORCEPROP 1 LAST HDL_TAP TRUE
J 0
(-2900 3875);
DISPLAY 0.872340 (-2900 3875);
DISPLAY INVISIBLE (-2900 3875);
FORCEPROP 1 LAST PATH I212
J 0
(-3227 4000);
DISPLAY 0.872340 (-3227 4000);
PAINT GREEN (-3227 4000);
DISPLAY INVISIBLE (-3227 4000);
FORCEADD TAP..1
(-3225 3900);
FORCEPROP 3 LASTPIN (-3275 3900) SIG_NAME M_A_CPU1_SA_DQS_DP<2>
J 0
(-3265 3910);
DISPLAY 0.659574 (-3265 3910);
PAINT MONO (-3265 3910);
DISPLAY INVISIBLE (-3265 3910);
FORCEPROP 1 LASTPIN (-3275 3900) BN 2
J 0
(-3287 3908);
DISPLAY 0.489362 (-3287 3908);
PAINT GREEN (-3287 3908);
FORCEPROP 2 LAST CDS_LIB mstr_standard
J 0
(-3225 3900);
DISPLAY 0.723404 (-3225 3900);
PAINT MONO (-3225 3900);
DISPLAY INVISIBLE (-3225 3900);
FORCEPROP 1 LAST BODY_TYPE PLUMBING
J 0
(-3225 3950);
DISPLAY 0.872340 (-3225 3950);
PAINT GREEN (-3225 3950);
DISPLAY INVISIBLE (-3225 3950);
FORCEPROP 1 LAST HDL_TAP TRUE
J 0
(-2900 3775);
DISPLAY 0.872340 (-2900 3775);
DISPLAY INVISIBLE (-2900 3775);
FORCEPROP 1 LAST PATH I213
J 0
(-3227 3900);
DISPLAY 0.872340 (-3227 3900);
PAINT GREEN (-3227 3900);
DISPLAY INVISIBLE (-3227 3900);
FORCEADD TAP..1
(-3025 3750);
FORCEPROP 3 LASTPIN (-3075 3750) SIG_NAME M_A_CPU1_SA_DQS_DN<1>
J 0
(-3065 3760);
DISPLAY 0.659574 (-3065 3760);
PAINT MONO (-3065 3760);
DISPLAY INVISIBLE (-3065 3760);
FORCEPROP 1 LASTPIN (-3075 3750) BN 1
J 0
(-3087 3758);
DISPLAY 0.489362 (-3087 3758);
PAINT GREEN (-3087 3758);
FORCEPROP 2 LAST CDS_LIB mstr_standard
J 0
(-3025 3750);
DISPLAY 0.723404 (-3025 3750);
PAINT MONO (-3025 3750);
DISPLAY INVISIBLE (-3025 3750);
FORCEPROP 1 LAST BODY_TYPE PLUMBING
J 0
(-3025 3800);
DISPLAY 0.872340 (-3025 3800);
PAINT GREEN (-3025 3800);
DISPLAY INVISIBLE (-3025 3800);
FORCEPROP 1 LAST HDL_TAP TRUE
J 0
(-2700 3625);
DISPLAY 0.872340 (-2700 3625);
DISPLAY INVISIBLE (-2700 3625);
FORCEPROP 1 LAST PATH I214
J 0
(-3027 3750);
DISPLAY 0.872340 (-3027 3750);
PAINT GREEN (-3027 3750);
DISPLAY INVISIBLE (-3027 3750);
FORCEADD TAP..1
(-3025 3650);
FORCEPROP 3 LASTPIN (-3075 3650) SIG_NAME M_A_CPU1_SA_DQS_DN<0>
J 0
(-3065 3660);
DISPLAY 0.659574 (-3065 3660);
PAINT MONO (-3065 3660);
DISPLAY INVISIBLE (-3065 3660);
FORCEPROP 1 LASTPIN (-3075 3650) BN 0
J 0
(-3087 3658);
DISPLAY 0.489362 (-3087 3658);
PAINT GREEN (-3087 3658);
FORCEPROP 2 LAST CDS_LIB mstr_standard
J 0
(-3025 3650);
DISPLAY 0.723404 (-3025 3650);
PAINT MONO (-3025 3650);
DISPLAY INVISIBLE (-3025 3650);
FORCEPROP 1 LAST BODY_TYPE PLUMBING
J 0
(-3025 3700);
DISPLAY 0.872340 (-3025 3700);
PAINT GREEN (-3025 3700);
DISPLAY INVISIBLE (-3025 3700);
FORCEPROP 1 LAST HDL_TAP TRUE
J 0
(-2700 3525);
DISPLAY 0.872340 (-2700 3525);
DISPLAY INVISIBLE (-2700 3525);
FORCEPROP 1 LAST PATH I215
J 0
(-3027 3650);
DISPLAY 0.872340 (-3027 3650);
PAINT GREEN (-3027 3650);
DISPLAY INVISIBLE (-3027 3650);
FORCEADD TAP..1
(-3025 3500);
FORCEPROP 3 LASTPIN (-3075 3500) SIG_NAME M_A_CPU1_SB_DQS_DN<9>
J 0
(-3065 3510);
DISPLAY 0.659574 (-3065 3510);
PAINT MONO (-3065 3510);
DISPLAY INVISIBLE (-3065 3510);
FORCEPROP 1 LASTPIN (-3075 3500) BN 9
J 0
(-3087 3508);
DISPLAY 0.489362 (-3087 3508);
PAINT GREEN (-3087 3508);
FORCEPROP 2 LAST CDS_LIB mstr_standard
J 0
(-3025 3500);
DISPLAY 0.723404 (-3025 3500);
PAINT MONO (-3025 3500);
DISPLAY INVISIBLE (-3025 3500);
FORCEPROP 1 LAST BODY_TYPE PLUMBING
J 0
(-3025 3550);
DISPLAY 0.872340 (-3025 3550);
PAINT GREEN (-3025 3550);
DISPLAY INVISIBLE (-3025 3550);
FORCEPROP 1 LAST HDL_TAP TRUE
J 0
(-2700 3375);
DISPLAY 0.872340 (-2700 3375);
DISPLAY INVISIBLE (-2700 3375);
FORCEPROP 1 LAST PATH I216
J 0
(-3027 3500);
DISPLAY 0.872340 (-3027 3500);
PAINT GREEN (-3027 3500);
DISPLAY INVISIBLE (-3027 3500);
FORCEADD TAP..1
(-3025 3400);
FORCEPROP 3 LASTPIN (-3075 3400) SIG_NAME M_A_CPU1_SB_DQS_DN<8>
J 0
(-3065 3410);
DISPLAY 0.659574 (-3065 3410);
PAINT MONO (-3065 3410);
DISPLAY INVISIBLE (-3065 3410);
FORCEPROP 1 LASTPIN (-3075 3400) BN 8
J 0
(-3087 3408);
DISPLAY 0.489362 (-3087 3408);
PAINT GREEN (-3087 3408);
FORCEPROP 2 LAST CDS_LIB mstr_standard
J 0
(-3025 3400);
DISPLAY 0.723404 (-3025 3400);
PAINT MONO (-3025 3400);
DISPLAY INVISIBLE (-3025 3400);
FORCEPROP 1 LAST BODY_TYPE PLUMBING
J 0
(-3025 3450);
DISPLAY 0.872340 (-3025 3450);
PAINT GREEN (-3025 3450);
DISPLAY INVISIBLE (-3025 3450);
FORCEPROP 1 LAST HDL_TAP TRUE
J 0
(-2700 3275);
DISPLAY 0.872340 (-2700 3275);
DISPLAY INVISIBLE (-2700 3275);
FORCEPROP 1 LAST PATH I217
J 0
(-3027 3400);
DISPLAY 0.872340 (-3027 3400);
PAINT GREEN (-3027 3400);
DISPLAY INVISIBLE (-3027 3400);
FORCEADD TAP..1
(-3025 3300);
FORCEPROP 3 LASTPIN (-3075 3300) SIG_NAME M_A_CPU1_SB_DQS_DN<7>
J 0
(-3065 3310);
DISPLAY 0.659574 (-3065 3310);
PAINT MONO (-3065 3310);
DISPLAY INVISIBLE (-3065 3310);
FORCEPROP 1 LASTPIN (-3075 3300) BN 7
J 0
(-3087 3308);
DISPLAY 0.489362 (-3087 3308);
PAINT GREEN (-3087 3308);
FORCEPROP 2 LAST CDS_LIB mstr_standard
J 0
(-3025 3300);
DISPLAY 0.723404 (-3025 3300);
PAINT MONO (-3025 3300);
DISPLAY INVISIBLE (-3025 3300);
FORCEPROP 1 LAST BODY_TYPE PLUMBING
J 0
(-3025 3350);
DISPLAY 0.872340 (-3025 3350);
PAINT GREEN (-3025 3350);
DISPLAY INVISIBLE (-3025 3350);
FORCEPROP 1 LAST HDL_TAP TRUE
J 0
(-2700 3175);
DISPLAY 0.872340 (-2700 3175);
DISPLAY INVISIBLE (-2700 3175);
FORCEPROP 1 LAST PATH I218
J 0
(-3027 3300);
DISPLAY 0.872340 (-3027 3300);
PAINT GREEN (-3027 3300);
DISPLAY INVISIBLE (-3027 3300);
FORCEADD TAP..1
(-3225 3700);
FORCEPROP 3 LASTPIN (-3275 3700) SIG_NAME M_A_CPU1_SA_DQS_DP<0>
J 0
(-3265 3710);
DISPLAY 0.659574 (-3265 3710);
PAINT MONO (-3265 3710);
DISPLAY INVISIBLE (-3265 3710);
FORCEPROP 1 LASTPIN (-3275 3700) BN 0
J 0
(-3287 3708);
DISPLAY 0.489362 (-3287 3708);
PAINT GREEN (-3287 3708);
FORCEPROP 2 LAST CDS_LIB mstr_standard
J 0
(-3225 3700);
DISPLAY 0.723404 (-3225 3700);
PAINT MONO (-3225 3700);
DISPLAY INVISIBLE (-3225 3700);
FORCEPROP 1 LAST BODY_TYPE PLUMBING
J 0
(-3225 3750);
DISPLAY 0.872340 (-3225 3750);
PAINT GREEN (-3225 3750);
DISPLAY INVISIBLE (-3225 3750);
FORCEPROP 1 LAST HDL_TAP TRUE
J 0
(-2900 3575);
DISPLAY 0.872340 (-2900 3575);
DISPLAY INVISIBLE (-2900 3575);
FORCEPROP 1 LAST PATH I219
J 0
(-3227 3700);
DISPLAY 0.872340 (-3227 3700);
PAINT GREEN (-3227 3700);
DISPLAY INVISIBLE (-3227 3700);
FORCEADD SCONN288_DDR506112002KQ..1
(-6600 3725);
FORCEPROP 1 LAST LOCATION J24
J 0
(-7050 5800);
DISPLAY 0.468085 (-7050 5800);
PAINT SKYBLUE (-7050 5800);
FORCEPROP 0 LAST $SEC 1
J 0
(-7050 5950);
DISPLAY 0.680851 (-7050 5950);
PAINT MONO (-7050 5950);
DISPLAY INVISIBLE (-7050 5950);
FORCEPROP 0 LAST CDS_SEC 1
J 0
(-7050 5950);
DISPLAY 0.680851 (-7050 5950);
DISPLAY INVISIBLE (-7050 5950);
FORCEPROP 0 LASTPIN (-7200 3125) $PN 62
J 2
(-7210 3135);
DISPLAY 0.680851 (-7210 3135);
PAINT MONO (-7210 3135);
FORCEPROP 0 LASTPIN (-7200 5175) $PN 66
J 2
(-7210 5185);
DISPLAY 0.680851 (-7210 5185);
PAINT MONO (-7210 5185);
FORCEPROP 0 LASTPIN (-7200 4775) $PN 76
J 2
(-7210 4785);
DISPLAY 0.680851 (-7210 4785);
PAINT MONO (-7210 4785);
FORCEPROP 0 LASTPIN (-7200 5225) $PN 211
J 2
(-7210 5235);
DISPLAY 0.680851 (-7210 5235);
PAINT MONO (-7210 5235);
FORCEPROP 0 LASTPIN (-7200 4825) $PN 221
J 2
(-7210 4835);
DISPLAY 0.680851 (-7210 4835);
PAINT MONO (-7210 4835);
FORCEPROP 0 LASTPIN (-7200 5275) $PN 68
J 2
(-7210 5285);
DISPLAY 0.680851 (-7210 5285);
PAINT MONO (-7210 5285);
FORCEPROP 0 LASTPIN (-7200 4875) $PN 78
J 2
(-7210 4885);
DISPLAY 0.680851 (-7210 4885);
PAINT MONO (-7210 4885);
FORCEPROP 0 LASTPIN (-7200 5325) $PN 213
J 2
(-7210 5335);
DISPLAY 0.680851 (-7210 5335);
PAINT MONO (-7210 5335);
FORCEPROP 0 LASTPIN (-7200 4925) $PN 223
J 2
(-7210 4935);
DISPLAY 0.680851 (-7210 4935);
PAINT MONO (-7210 4935);
FORCEPROP 0 LASTPIN (-7200 5375) $PN 70
J 2
(-7210 5385);
DISPLAY 0.680851 (-7210 5385);
PAINT MONO (-7210 5385);
FORCEPROP 0 LASTPIN (-7200 4975) $PN 80
J 2
(-7210 4985);
DISPLAY 0.680851 (-7210 4985);
PAINT MONO (-7210 4985);
FORCEPROP 0 LASTPIN (-7200 5425) $PN 215
J 2
(-7210 5435);
DISPLAY 0.680851 (-7210 5435);
PAINT MONO (-7210 5435);
FORCEPROP 0 LASTPIN (-7200 5025) $PN 225
J 2
(-7210 5035);
DISPLAY 0.680851 (-7210 5035);
PAINT MONO (-7210 5035);
FORCEPROP 0 LASTPIN (-7200 5475) $PN 72
J 2
(-7210 5485);
DISPLAY 0.680851 (-7210 5485);
PAINT MONO (-7210 5485);
FORCEPROP 0 LASTPIN (-7200 5075) $PN 82
J 2
(-7210 5085);
DISPLAY 0.680851 (-7210 5085);
PAINT MONO (-7210 5085);
FORCEPROP 0 LASTPIN (-7200 3725) $PN 51
J 2
(-7210 3735);
DISPLAY 0.680851 (-7210 3735);
PAINT MONO (-7210 3735);
FORCEPROP 0 LASTPIN (-7200 3275) $PN 96
J 2
(-7210 3285);
DISPLAY 0.680851 (-7210 3285);
PAINT MONO (-7210 3285);
FORCEPROP 0 LASTPIN (-7200 3775) $PN 53
J 2
(-7210 3785);
DISPLAY 0.680851 (-7210 3785);
PAINT MONO (-7210 3785);
FORCEPROP 0 LASTPIN (-7200 3325) $PN 98
J 2
(-7210 3335);
DISPLAY 0.680851 (-7210 3335);
PAINT MONO (-7210 3335);
FORCEPROP 0 LASTPIN (-7200 3825) $PN 196
J 2
(-7210 3835);
DISPLAY 0.680851 (-7210 3835);
PAINT MONO (-7210 3835);
FORCEPROP 0 LASTPIN (-7200 3375) $PN 241
J 2
(-7210 3385);
DISPLAY 0.680851 (-7210 3385);
PAINT MONO (-7210 3385);
FORCEPROP 0 LASTPIN (-7200 3875) $PN 198
J 2
(-7210 3885);
DISPLAY 0.680851 (-7210 3885);
PAINT MONO (-7210 3885);
FORCEPROP 0 LASTPIN (-7200 3425) $PN 243
J 2
(-7210 3435);
DISPLAY 0.680851 (-7210 3435);
PAINT MONO (-7210 3435);
FORCEPROP 0 LASTPIN (-7200 3925) $PN 58
J 2
(-7210 3935);
DISPLAY 0.680851 (-7210 3935);
PAINT MONO (-7210 3935);
FORCEPROP 0 LASTPIN (-7200 3475) $PN 89
J 2
(-7210 3485);
DISPLAY 0.680851 (-7210 3485);
PAINT MONO (-7210 3485);
FORCEPROP 0 LASTPIN (-7200 3975) $PN 60
J 2
(-7210 3985);
DISPLAY 0.680851 (-7210 3985);
PAINT MONO (-7210 3985);
FORCEPROP 0 LASTPIN (-7200 3525) $PN 91
J 2
(-7210 3535);
DISPLAY 0.680851 (-7210 3535);
PAINT MONO (-7210 3535);
FORCEPROP 0 LASTPIN (-7200 4025) $PN 203
J 2
(-7210 4035);
DISPLAY 0.680851 (-7210 4035);
PAINT MONO (-7210 4035);
FORCEPROP 0 LASTPIN (-7200 3575) $PN 234
J 2
(-7210 3585);
DISPLAY 0.680851 (-7210 3585);
PAINT MONO (-7210 3585);
FORCEPROP 0 LASTPIN (-7200 4075) $PN 205
J 2
(-7210 4085);
DISPLAY 0.680851 (-7210 4085);
PAINT MONO (-7210 4085);
FORCEPROP 0 LASTPIN (-7200 3625) $PN 236
J 2
(-7210 3635);
DISPLAY 0.680851 (-7210 3635);
PAINT MONO (-7210 3635);
FORCEPROP 0 LASTPIN (-7200 4175) $PN 218
J 2
(-7210 4185);
DISPLAY 0.680851 (-7210 4185);
PAINT MONO (-7210 4185);
FORCEPROP 0 LASTPIN (-7200 4225) $PN 217
J 2
(-7210 4235);
DISPLAY 0.680851 (-7210 4235);
PAINT MONO (-7210 4235);
FORCEPROP 0 LASTPIN (-7200 4475) $PN 64
J 2
(-7210 4485);
DISPLAY 0.680851 (-7210 4485);
PAINT MONO (-7210 4485);
FORCEPROP 0 LASTPIN (-7200 4325) $PN 84
J 2
(-7210 4335);
DISPLAY 0.680851 (-7210 4335);
PAINT MONO (-7210 4335);
FORCEPROP 0 LASTPIN (-7200 4525) $PN 209
J 2
(-7210 4535);
DISPLAY 0.680851 (-7210 4535);
PAINT MONO (-7210 4535);
FORCEPROP 0 LASTPIN (-7200 4375) $PN 229
J 2
(-7210 4385);
DISPLAY 0.680851 (-7210 4385);
PAINT MONO (-7210 4385);
FORCEPROP 0 LASTPIN (-6000 3925) $PN 7
J 0
(-5990 3935);
DISPLAY 0.680851 (-5990 3935);
PAINT MONO (-5990 3935);
FORCEPROP 0 LASTPIN (-6000 2275) $PN 100
J 0
(-5990 2285);
DISPLAY 0.680851 (-5990 2285);
PAINT MONO (-5990 2285);
FORCEPROP 0 LASTPIN (-6000 3975) $PN 9
J 0
(-5990 3985);
DISPLAY 0.680851 (-5990 3985);
PAINT MONO (-5990 3985);
FORCEPROP 0 LASTPIN (-6000 2325) $PN 102
J 0
(-5990 2335);
DISPLAY 0.680851 (-5990 2335);
PAINT MONO (-5990 2335);
FORCEPROP 0 LASTPIN (-6000 4025) $PN 152
J 0
(-5990 4035);
DISPLAY 0.680851 (-5990 4035);
PAINT MONO (-5990 4035);
FORCEPROP 0 LASTPIN (-6000 2375) $PN 245
J 0
(-5990 2385);
DISPLAY 0.680851 (-5990 2385);
PAINT MONO (-5990 2385);
FORCEPROP 0 LASTPIN (-6000 4075) $PN 154
J 0
(-5990 4085);
DISPLAY 0.680851 (-5990 4085);
PAINT MONO (-5990 4085);
FORCEPROP 0 LASTPIN (-6000 2425) $PN 247
J 0
(-5990 2435);
DISPLAY 0.680851 (-5990 2435);
PAINT MONO (-5990 2435);
FORCEPROP 0 LASTPIN (-6000 4125) $PN 14
J 0
(-5990 4135);
DISPLAY 0.680851 (-5990 4135);
PAINT MONO (-5990 4135);
FORCEPROP 0 LASTPIN (-6000 2475) $PN 107
J 0
(-5990 2485);
DISPLAY 0.680851 (-5990 2485);
PAINT MONO (-5990 2485);
FORCEPROP 0 LASTPIN (-6000 4175) $PN 16
J 0
(-5990 4185);
DISPLAY 0.680851 (-5990 4185);
PAINT MONO (-5990 4185);
FORCEPROP 0 LASTPIN (-6000 2525) $PN 109
J 0
(-5990 2535);
DISPLAY 0.680851 (-5990 2535);
PAINT MONO (-5990 2535);
FORCEPROP 0 LASTPIN (-6000 4225) $PN 159
J 0
(-5990 4235);
DISPLAY 0.680851 (-5990 4235);
PAINT MONO (-5990 4235);
FORCEPROP 0 LASTPIN (-6000 2575) $PN 252
J 0
(-5990 2585);
DISPLAY 0.680851 (-5990 2585);
PAINT MONO (-5990 2585);
FORCEPROP 0 LASTPIN (-6000 4275) $PN 161
J 0
(-5990 4285);
DISPLAY 0.680851 (-5990 4285);
PAINT MONO (-5990 4285);
FORCEPROP 0 LASTPIN (-6000 2625) $PN 254
J 0
(-5990 2635);
DISPLAY 0.680851 (-5990 2635);
PAINT MONO (-5990 2635);
FORCEPROP 0 LASTPIN (-6000 4325) $PN 18
J 0
(-5990 4335);
DISPLAY 0.680851 (-5990 4335);
PAINT MONO (-5990 4335);
FORCEPROP 0 LASTPIN (-6000 2675) $PN 111
J 0
(-5990 2685);
DISPLAY 0.680851 (-5990 2685);
PAINT MONO (-5990 2685);
FORCEPROP 0 LASTPIN (-6000 4375) $PN 20
J 0
(-5990 4385);
DISPLAY 0.680851 (-5990 4385);
PAINT MONO (-5990 4385);
FORCEPROP 0 LASTPIN (-6000 2725) $PN 113
J 0
(-5990 2735);
DISPLAY 0.680851 (-5990 2735);
PAINT MONO (-5990 2735);
FORCEPROP 0 LASTPIN (-6000 4425) $PN 163
J 0
(-5990 4435);
DISPLAY 0.680851 (-5990 4435);
PAINT MONO (-5990 4435);
FORCEPROP 0 LASTPIN (-6000 2775) $PN 256
J 0
(-5990 2785);
DISPLAY 0.680851 (-5990 2785);
PAINT MONO (-5990 2785);
FORCEPROP 0 LASTPIN (-6000 4475) $PN 165
J 0
(-5990 4485);
DISPLAY 0.680851 (-5990 4485);
PAINT MONO (-5990 4485);
FORCEPROP 0 LASTPIN (-6000 2825) $PN 258
J 0
(-5990 2835);
DISPLAY 0.680851 (-5990 2835);
PAINT MONO (-5990 2835);
FORCEPROP 0 LASTPIN (-6000 4525) $PN 25
J 0
(-5990 4535);
DISPLAY 0.680851 (-5990 4535);
PAINT MONO (-5990 4535);
FORCEPROP 0 LASTPIN (-6000 2875) $PN 118
J 0
(-5990 2885);
DISPLAY 0.680851 (-5990 2885);
PAINT MONO (-5990 2885);
FORCEPROP 0 LASTPIN (-6000 4575) $PN 27
J 0
(-5990 4585);
DISPLAY 0.680851 (-5990 4585);
PAINT MONO (-5990 4585);
FORCEPROP 0 LASTPIN (-6000 2925) $PN 120
J 0
(-5990 2935);
DISPLAY 0.680851 (-5990 2935);
PAINT MONO (-5990 2935);
FORCEPROP 0 LASTPIN (-6000 4625) $PN 170
J 0
(-5990 4635);
DISPLAY 0.680851 (-5990 4635);
PAINT MONO (-5990 4635);
FORCEPROP 0 LASTPIN (-6000 2975) $PN 263
J 0
(-5990 2985);
DISPLAY 0.680851 (-5990 2985);
PAINT MONO (-5990 2985);
FORCEPROP 0 LASTPIN (-6000 4675) $PN 172
J 0
(-5990 4685);
DISPLAY 0.680851 (-5990 4685);
PAINT MONO (-5990 4685);
FORCEPROP 0 LASTPIN (-6000 3025) $PN 265
J 0
(-5990 3035);
DISPLAY 0.680851 (-5990 3035);
PAINT MONO (-5990 3035);
FORCEPROP 0 LASTPIN (-6000 4725) $PN 29
J 0
(-5990 4735);
DISPLAY 0.680851 (-5990 4735);
PAINT MONO (-5990 4735);
FORCEPROP 0 LASTPIN (-6000 3075) $PN 122
J 0
(-5990 3085);
DISPLAY 0.680851 (-5990 3085);
PAINT MONO (-5990 3085);
FORCEPROP 0 LASTPIN (-6000 4775) $PN 31
J 0
(-5990 4785);
DISPLAY 0.680851 (-5990 4785);
PAINT MONO (-5990 4785);
FORCEPROP 0 LASTPIN (-6000 3125) $PN 124
J 0
(-5990 3135);
DISPLAY 0.680851 (-5990 3135);
PAINT MONO (-5990 3135);
FORCEPROP 0 LASTPIN (-6000 4825) $PN 174
J 0
(-5990 4835);
DISPLAY 0.680851 (-5990 4835);
PAINT MONO (-5990 4835);
FORCEPROP 0 LASTPIN (-6000 3175) $PN 267
J 0
(-5990 3185);
DISPLAY 0.680851 (-5990 3185);
PAINT MONO (-5990 3185);
FORCEPROP 0 LASTPIN (-6000 4875) $PN 176
J 0
(-5990 4885);
DISPLAY 0.680851 (-5990 4885);
PAINT MONO (-5990 4885);
FORCEPROP 0 LASTPIN (-6000 3225) $PN 269
J 0
(-5990 3235);
DISPLAY 0.680851 (-5990 3235);
PAINT MONO (-5990 3235);
FORCEPROP 0 LASTPIN (-6000 4925) $PN 36
J 0
(-5990 4935);
DISPLAY 0.680851 (-5990 4935);
PAINT MONO (-5990 4935);
FORCEPROP 0 LASTPIN (-6000 3275) $PN 129
J 0
(-5990 3285);
DISPLAY 0.680851 (-5990 3285);
PAINT MONO (-5990 3285);
FORCEPROP 0 LASTPIN (-6000 4975) $PN 38
J 0
(-5990 4985);
DISPLAY 0.680851 (-5990 4985);
PAINT MONO (-5990 4985);
FORCEPROP 0 LASTPIN (-6000 3325) $PN 131
J 0
(-5990 3335);
DISPLAY 0.680851 (-5990 3335);
PAINT MONO (-5990 3335);
FORCEPROP 0 LASTPIN (-6000 5025) $PN 181
J 0
(-5990 5035);
DISPLAY 0.680851 (-5990 5035);
PAINT MONO (-5990 5035);
FORCEPROP 0 LASTPIN (-6000 3375) $PN 274
J 0
(-5990 3385);
DISPLAY 0.680851 (-5990 3385);
PAINT MONO (-5990 3385);
FORCEPROP 0 LASTPIN (-6000 5075) $PN 183
J 0
(-5990 5085);
DISPLAY 0.680851 (-5990 5085);
PAINT MONO (-5990 5085);
FORCEPROP 0 LASTPIN (-6000 3425) $PN 276
J 0
(-5990 3435);
DISPLAY 0.680851 (-5990 3435);
PAINT MONO (-5990 3435);
FORCEPROP 0 LASTPIN (-6000 5125) $PN 40
J 0
(-5990 5135);
DISPLAY 0.680851 (-5990 5135);
PAINT MONO (-5990 5135);
FORCEPROP 0 LASTPIN (-6000 3475) $PN 133
J 0
(-5990 3485);
DISPLAY 0.680851 (-5990 3485);
PAINT MONO (-5990 3485);
FORCEPROP 0 LASTPIN (-6000 5175) $PN 42
J 0
(-5990 5185);
DISPLAY 0.680851 (-5990 5185);
PAINT MONO (-5990 5185);
FORCEPROP 0 LASTPIN (-6000 3525) $PN 135
J 0
(-5990 3535);
DISPLAY 0.680851 (-5990 3535);
PAINT MONO (-5990 3535);
FORCEPROP 0 LASTPIN (-6000 5225) $PN 185
J 0
(-5990 5235);
DISPLAY 0.680851 (-5990 5235);
PAINT MONO (-5990 5235);
FORCEPROP 0 LASTPIN (-6000 3575) $PN 278
J 0
(-5990 3585);
DISPLAY 0.680851 (-5990 3585);
PAINT MONO (-5990 3585);
FORCEPROP 0 LASTPIN (-6000 5275) $PN 187
J 0
(-5990 5285);
DISPLAY 0.680851 (-5990 5285);
PAINT MONO (-5990 5285);
FORCEPROP 0 LASTPIN (-6000 3625) $PN 280
J 0
(-5990 3635);
DISPLAY 0.680851 (-5990 3635);
PAINT MONO (-5990 3635);
FORCEPROP 0 LASTPIN (-6000 5325) $PN 47
J 0
(-5990 5335);
DISPLAY 0.680851 (-5990 5335);
PAINT MONO (-5990 5335);
FORCEPROP 0 LASTPIN (-6000 3675) $PN 140
J 0
(-5990 3685);
DISPLAY 0.680851 (-5990 3685);
PAINT MONO (-5990 3685);
FORCEPROP 0 LASTPIN (-6000 5375) $PN 49
J 0
(-5990 5385);
DISPLAY 0.680851 (-5990 5385);
PAINT MONO (-5990 5385);
FORCEPROP 0 LASTPIN (-6000 3725) $PN 142
J 0
(-5990 3735);
DISPLAY 0.680851 (-5990 3735);
PAINT MONO (-5990 3735);
FORCEPROP 0 LASTPIN (-6000 5425) $PN 192
J 0
(-5990 5435);
DISPLAY 0.680851 (-5990 5435);
PAINT MONO (-5990 5435);
FORCEPROP 0 LASTPIN (-6000 3775) $PN 285
J 0
(-5990 3785);
DISPLAY 0.680851 (-5990 3785);
PAINT MONO (-5990 3785);
FORCEPROP 0 LASTPIN (-6000 5475) $PN 194
J 0
(-5990 5485);
DISPLAY 0.680851 (-5990 5485);
PAINT MONO (-5990 5485);
FORCEPROP 0 LASTPIN (-6000 3825) $PN 287
J 0
(-5990 3835);
DISPLAY 0.680851 (-5990 3835);
PAINT MONO (-5990 3835);
FORCEPROP 0 LASTPIN (-7200 2975) $PN 148
J 2
(-7210 2985);
DISPLAY 0.680851 (-7210 2985);
PAINT MONO (-7210 2985);
FORCEPROP 0 LASTPIN (-7200 2875) $PN 4
J 2
(-7210 2885);
DISPLAY 0.680851 (-7210 2885);
PAINT MONO (-7210 2885);
FORCEPROP 0 LASTPIN (-7200 2925) $PN 5
J 2
(-7210 2935);
DISPLAY 0.680851 (-7210 2935);
PAINT MONO (-7210 2935);
FORCEPROP 0 LASTPIN (-7200 2075) $PN 86
J 2
(-7210 2085);
DISPLAY 0.680851 (-7210 2085);
PAINT MONO (-7210 2085);
FORCEPROP 0 LASTPIN (-7200 2025) $PN 87
J 2
(-7210 2035);
DISPLAY 0.680851 (-7210 2035);
PAINT MONO (-7210 2035);
FORCEPROP 0 LASTPIN (-7200 4675) $PN 74
J 2
(-7210 4685);
DISPLAY 0.680851 (-7210 4685);
PAINT MONO (-7210 4685);
FORCEPROP 0 LASTPIN (-7200 4625) $PN 227
J 2
(-7210 4635);
DISPLAY 0.680851 (-7210 4635);
PAINT MONO (-7210 4635);
FORCEPROP 0 LASTPIN (-7200 2625) $PN 147
J 2
(-7210 2635);
DISPLAY 0.680851 (-7210 2635);
PAINT MONO (-7210 2635);
FORCEPROP 0 LASTPIN (-7200 3175) $PN 207
J 2
(-7210 3185);
DISPLAY 0.680851 (-7210 3185);
PAINT MONO (-7210 3185);
FORCEPROP 0 LASTPIN (-7200 2225) $PN 2
J 2
(-7210 2235);
DISPLAY 0.680851 (-7210 2235);
PAINT MONO (-7210 2235);
FORCEPROP 0 LASTPIN (-7200 2275) $PN 144
J 2
(-7210 2285);
DISPLAY 0.680851 (-7210 2285);
PAINT MONO (-7210 2285);
FORCEPROP 0 LASTPIN (-7200 2325) $PN 149
J 2
(-7210 2335);
DISPLAY 0.680851 (-7210 2335);
PAINT MONO (-7210 2335);
FORCEPROP 0 LASTPIN (-7200 2375) $PN 150
J 2
(-7210 2385);
DISPLAY 0.680851 (-7210 2385);
PAINT MONO (-7210 2385);
FORCEPROP 0 LASTPIN (-7200 2425) $PN 220
J 2
(-7210 2435);
DISPLAY 0.680851 (-7210 2435);
PAINT MONO (-7210 2435);
FORCEPROP 0 LASTPIN (-7200 2475) $PN 231
J 2
(-7210 2485);
DISPLAY 0.680851 (-7210 2485);
PAINT MONO (-7210 2485);
FORCEPROP 0 LASTPIN (-7200 2525) $PN 232
J 2
(-7210 2535);
DISPLAY 0.680851 (-7210 2535);
PAINT MONO (-7210 2535);
FORCEPROP 0 LASTPIN (-7200 3025) $PN 3
J 2
(-7210 3035);
DISPLAY 0.680851 (-7210 3035);
PAINT MONO (-7210 3035);
FORCEPROP 2 LAST VALUE SCONN288_DDR506112002KQ
J 0
(-7050 5850);
DISPLAY 0.489362 (-7050 5850);
PAINT SKYBLUE (-7050 5850);
FORCEPROP 2 LAST PART_TYPE SMLF
J 0
(-7050 5900);
DISPLAY 1.021277 (-7050 5900);
FORCEPROP 1 LAST MATERIAL IO
J 0
(-7050 5650);
DISPLAY 0.468085 (-7050 5650);
PAINT SKYBLUE (-7050 5650);
FORCEPROP 1 LAST PART_NUMBER DFHST8FS479
J 0
(-7050 5725);
DISPLAY 0.468085 (-7050 5725);
PAINT SKYBLUE (-7050 5725);
FORCEPROP 1 LAST CDS_LMAN_SYM_OUTLINE -450,1900,450,-1850
J 0
(-6600 3725);
DISPLAY 0.468085 (-6600 3725);
PAINT GREEN (-6600 3725);
DISPLAY INVISIBLE (-6600 3725);
FORCEPROP 1 LAST PATH I22
J 0
(-6600 3725);
DISPLAY 0.723404 (-6600 3725);
PAINT GREEN (-6600 3725);
DISPLAY INVISIBLE (-6600 3725);
FORCEPROP 1 LAST NEEDS_NO_SIZE TRUE
J 0
(-6600 3725);
DISPLAY 0.723404 (-6600 3725);
PAINT GREEN (-6600 3725);
DISPLAY INVISIBLE (-6600 3725);
FORCEPROP 2 LAST CDS_LIB pure_quanta
J 0
(-6600 3725);
DISPLAY INVISIBLE (-6600 3725);
FORCEADD TAP..1
(-3225 3800);
FORCEPROP 3 LASTPIN (-3275 3800) SIG_NAME M_A_CPU1_SA_DQS_DP<1>
J 0
(-3265 3810);
DISPLAY 0.659574 (-3265 3810);
PAINT MONO (-3265 3810);
DISPLAY INVISIBLE (-3265 3810);
FORCEPROP 1 LASTPIN (-3275 3800) BN 1
J 0
(-3287 3808);
DISPLAY 0.489362 (-3287 3808);
PAINT GREEN (-3287 3808);
FORCEPROP 2 LAST CDS_LIB mstr_standard
J 0
(-3225 3800);
DISPLAY 0.723404 (-3225 3800);
PAINT MONO (-3225 3800);
DISPLAY INVISIBLE (-3225 3800);
FORCEPROP 1 LAST BODY_TYPE PLUMBING
J 0
(-3225 3850);
DISPLAY 0.872340 (-3225 3850);
PAINT GREEN (-3225 3850);
DISPLAY INVISIBLE (-3225 3850);
FORCEPROP 1 LAST HDL_TAP TRUE
J 0
(-2900 3675);
DISPLAY 0.872340 (-2900 3675);
DISPLAY INVISIBLE (-2900 3675);
FORCEPROP 1 LAST PATH I220
J 0
(-3227 3800);
DISPLAY 0.872340 (-3227 3800);
PAINT GREEN (-3227 3800);
DISPLAY INVISIBLE (-3227 3800);
FORCEADD TAP..1
(-3225 3550);
FORCEPROP 3 LASTPIN (-3275 3550) SIG_NAME M_A_CPU1_SB_DQS_DP<9>
J 0
(-3265 3560);
DISPLAY 0.659574 (-3265 3560);
PAINT MONO (-3265 3560);
DISPLAY INVISIBLE (-3265 3560);
FORCEPROP 1 LASTPIN (-3275 3550) BN 9
J 0
(-3287 3558);
DISPLAY 0.489362 (-3287 3558);
PAINT GREEN (-3287 3558);
FORCEPROP 2 LAST CDS_LIB mstr_standard
J 0
(-3225 3550);
DISPLAY 0.723404 (-3225 3550);
PAINT MONO (-3225 3550);
DISPLAY INVISIBLE (-3225 3550);
FORCEPROP 1 LAST BODY_TYPE PLUMBING
J 0
(-3225 3600);
DISPLAY 0.872340 (-3225 3600);
PAINT GREEN (-3225 3600);
DISPLAY INVISIBLE (-3225 3600);
FORCEPROP 1 LAST HDL_TAP TRUE
J 0
(-2900 3425);
DISPLAY 0.872340 (-2900 3425);
DISPLAY INVISIBLE (-2900 3425);
FORCEPROP 1 LAST PATH I221
J 0
(-3227 3550);
DISPLAY 0.872340 (-3227 3550);
PAINT GREEN (-3227 3550);
DISPLAY INVISIBLE (-3227 3550);
FORCEADD TAP..1
(-3225 3450);
FORCEPROP 3 LASTPIN (-3275 3450) SIG_NAME M_A_CPU1_SB_DQS_DP<8>
J 0
(-3265 3460);
DISPLAY 0.659574 (-3265 3460);
PAINT MONO (-3265 3460);
DISPLAY INVISIBLE (-3265 3460);
FORCEPROP 1 LASTPIN (-3275 3450) BN 8
J 0
(-3287 3458);
DISPLAY 0.489362 (-3287 3458);
PAINT GREEN (-3287 3458);
FORCEPROP 2 LAST CDS_LIB mstr_standard
J 0
(-3225 3450);
DISPLAY 0.723404 (-3225 3450);
PAINT MONO (-3225 3450);
DISPLAY INVISIBLE (-3225 3450);
FORCEPROP 1 LAST BODY_TYPE PLUMBING
J 0
(-3225 3500);
DISPLAY 0.872340 (-3225 3500);
PAINT GREEN (-3225 3500);
DISPLAY INVISIBLE (-3225 3500);
FORCEPROP 1 LAST HDL_TAP TRUE
J 0
(-2900 3325);
DISPLAY 0.872340 (-2900 3325);
DISPLAY INVISIBLE (-2900 3325);
FORCEPROP 1 LAST PATH I222
J 0
(-3227 3450);
DISPLAY 0.872340 (-3227 3450);
PAINT GREEN (-3227 3450);
DISPLAY INVISIBLE (-3227 3450);
FORCEADD TAP..1
(-3225 3350);
FORCEPROP 3 LASTPIN (-3275 3350) SIG_NAME M_A_CPU1_SB_DQS_DP<7>
J 0
(-3265 3360);
DISPLAY 0.659574 (-3265 3360);
PAINT MONO (-3265 3360);
DISPLAY INVISIBLE (-3265 3360);
FORCEPROP 1 LASTPIN (-3275 3350) BN 7
J 0
(-3287 3358);
DISPLAY 0.489362 (-3287 3358);
PAINT GREEN (-3287 3358);
FORCEPROP 2 LAST CDS_LIB mstr_standard
J 0
(-3225 3350);
DISPLAY 0.723404 (-3225 3350);
PAINT MONO (-3225 3350);
DISPLAY INVISIBLE (-3225 3350);
FORCEPROP 1 LAST BODY_TYPE PLUMBING
J 0
(-3225 3400);
DISPLAY 0.872340 (-3225 3400);
PAINT GREEN (-3225 3400);
DISPLAY INVISIBLE (-3225 3400);
FORCEPROP 1 LAST HDL_TAP TRUE
J 0
(-2900 3225);
DISPLAY 0.872340 (-2900 3225);
DISPLAY INVISIBLE (-2900 3225);
FORCEPROP 1 LAST PATH I223
J 0
(-3227 3350);
DISPLAY 0.872340 (-3227 3350);
PAINT GREEN (-3227 3350);
DISPLAY INVISIBLE (-3227 3350);
FORCEADD TAP..1
(-3025 3200);
FORCEPROP 3 LASTPIN (-3075 3200) SIG_NAME M_A_CPU1_SB_DQS_DN<6>
J 0
(-3065 3210);
DISPLAY 0.659574 (-3065 3210);
PAINT MONO (-3065 3210);
DISPLAY INVISIBLE (-3065 3210);
FORCEPROP 1 LASTPIN (-3075 3200) BN 6
J 0
(-3087 3208);
DISPLAY 0.489362 (-3087 3208);
PAINT GREEN (-3087 3208);
FORCEPROP 2 LAST CDS_LIB mstr_standard
J 0
(-3025 3200);
DISPLAY 0.723404 (-3025 3200);
PAINT MONO (-3025 3200);
DISPLAY INVISIBLE (-3025 3200);
FORCEPROP 1 LAST BODY_TYPE PLUMBING
J 0
(-3025 3250);
DISPLAY 0.872340 (-3025 3250);
PAINT GREEN (-3025 3250);
DISPLAY INVISIBLE (-3025 3250);
FORCEPROP 1 LAST HDL_TAP TRUE
J 0
(-2700 3075);
DISPLAY 0.872340 (-2700 3075);
DISPLAY INVISIBLE (-2700 3075);
FORCEPROP 1 LAST PATH I224
J 0
(-3027 3200);
DISPLAY 0.872340 (-3027 3200);
PAINT GREEN (-3027 3200);
DISPLAY INVISIBLE (-3027 3200);
FORCEADD TAP..1
(-3025 3100);
FORCEPROP 3 LASTPIN (-3075 3100) SIG_NAME M_A_CPU1_SB_DQS_DN<5>
J 0
(-3065 3110);
DISPLAY 0.659574 (-3065 3110);
PAINT MONO (-3065 3110);
DISPLAY INVISIBLE (-3065 3110);
FORCEPROP 1 LASTPIN (-3075 3100) BN 5
J 0
(-3087 3108);
DISPLAY 0.489362 (-3087 3108);
PAINT GREEN (-3087 3108);
FORCEPROP 2 LAST CDS_LIB mstr_standard
J 0
(-3025 3100);
DISPLAY 0.723404 (-3025 3100);
PAINT MONO (-3025 3100);
DISPLAY INVISIBLE (-3025 3100);
FORCEPROP 1 LAST BODY_TYPE PLUMBING
J 0
(-3025 3150);
DISPLAY 0.872340 (-3025 3150);
PAINT GREEN (-3025 3150);
DISPLAY INVISIBLE (-3025 3150);
FORCEPROP 1 LAST HDL_TAP TRUE
J 0
(-2700 2975);
DISPLAY 0.872340 (-2700 2975);
DISPLAY INVISIBLE (-2700 2975);
FORCEPROP 1 LAST PATH I225
J 0
(-3027 3100);
DISPLAY 0.872340 (-3027 3100);
PAINT GREEN (-3027 3100);
DISPLAY INVISIBLE (-3027 3100);
FORCEADD TAP..1
(-3025 3000);
FORCEPROP 3 LASTPIN (-3075 3000) SIG_NAME M_A_CPU1_SB_DQS_DN<4>
J 0
(-3065 3010);
DISPLAY 0.659574 (-3065 3010);
PAINT MONO (-3065 3010);
DISPLAY INVISIBLE (-3065 3010);
FORCEPROP 1 LASTPIN (-3075 3000) BN 4
J 0
(-3087 3008);
DISPLAY 0.489362 (-3087 3008);
PAINT GREEN (-3087 3008);
FORCEPROP 2 LAST CDS_LIB mstr_standard
J 0
(-3025 3000);
DISPLAY 0.723404 (-3025 3000);
PAINT MONO (-3025 3000);
DISPLAY INVISIBLE (-3025 3000);
FORCEPROP 1 LAST BODY_TYPE PLUMBING
J 0
(-3025 3050);
DISPLAY 0.872340 (-3025 3050);
PAINT GREEN (-3025 3050);
DISPLAY INVISIBLE (-3025 3050);
FORCEPROP 1 LAST HDL_TAP TRUE
J 0
(-2700 2875);
DISPLAY 0.872340 (-2700 2875);
DISPLAY INVISIBLE (-2700 2875);
FORCEPROP 1 LAST PATH I226
J 0
(-3027 3000);
DISPLAY 0.872340 (-3027 3000);
PAINT GREEN (-3027 3000);
DISPLAY INVISIBLE (-3027 3000);
FORCEADD TAP..1
(-3025 2800);
FORCEPROP 3 LASTPIN (-3075 2800) SIG_NAME M_A_CPU1_SB_DQS_DN<2>
J 0
(-3065 2810);
DISPLAY 0.659574 (-3065 2810);
PAINT MONO (-3065 2810);
DISPLAY INVISIBLE (-3065 2810);
FORCEPROP 1 LASTPIN (-3075 2800) BN 2
J 0
(-3087 2808);
DISPLAY 0.489362 (-3087 2808);
PAINT GREEN (-3087 2808);
FORCEPROP 2 LAST CDS_LIB mstr_standard
J 0
(-3025 2800);
DISPLAY 0.723404 (-3025 2800);
PAINT MONO (-3025 2800);
DISPLAY INVISIBLE (-3025 2800);
FORCEPROP 1 LAST BODY_TYPE PLUMBING
J 0
(-3025 2850);
DISPLAY 0.872340 (-3025 2850);
PAINT GREEN (-3025 2850);
DISPLAY INVISIBLE (-3025 2850);
FORCEPROP 1 LAST HDL_TAP TRUE
J 0
(-2700 2675);
DISPLAY 0.872340 (-2700 2675);
DISPLAY INVISIBLE (-2700 2675);
FORCEPROP 1 LAST PATH I227
J 0
(-3027 2800);
DISPLAY 0.872340 (-3027 2800);
PAINT GREEN (-3027 2800);
DISPLAY INVISIBLE (-3027 2800);
FORCEADD TAP..1
(-3025 2900);
FORCEPROP 3 LASTPIN (-3075 2900) SIG_NAME M_A_CPU1_SB_DQS_DN<3>
J 0
(-3065 2910);
DISPLAY 0.659574 (-3065 2910);
PAINT MONO (-3065 2910);
DISPLAY INVISIBLE (-3065 2910);
FORCEPROP 1 LASTPIN (-3075 2900) BN 3
J 0
(-3087 2908);
DISPLAY 0.489362 (-3087 2908);
PAINT GREEN (-3087 2908);
FORCEPROP 2 LAST CDS_LIB mstr_standard
J 0
(-3025 2900);
DISPLAY 0.723404 (-3025 2900);
PAINT MONO (-3025 2900);
DISPLAY INVISIBLE (-3025 2900);
FORCEPROP 1 LAST BODY_TYPE PLUMBING
J 0
(-3025 2950);
DISPLAY 0.872340 (-3025 2950);
PAINT GREEN (-3025 2950);
DISPLAY INVISIBLE (-3025 2950);
FORCEPROP 1 LAST HDL_TAP TRUE
J 0
(-2700 2775);
DISPLAY 0.872340 (-2700 2775);
DISPLAY INVISIBLE (-2700 2775);
FORCEPROP 1 LAST PATH I228
J 0
(-3027 2900);
DISPLAY 0.872340 (-3027 2900);
PAINT GREEN (-3027 2900);
DISPLAY INVISIBLE (-3027 2900);
FORCEADD TAP..1
(-3225 3250);
FORCEPROP 3 LASTPIN (-3275 3250) SIG_NAME M_A_CPU1_SB_DQS_DP<6>
J 0
(-3265 3260);
DISPLAY 0.659574 (-3265 3260);
PAINT MONO (-3265 3260);
DISPLAY INVISIBLE (-3265 3260);
FORCEPROP 1 LASTPIN (-3275 3250) BN 6
J 0
(-3287 3258);
DISPLAY 0.489362 (-3287 3258);
PAINT GREEN (-3287 3258);
FORCEPROP 2 LAST CDS_LIB mstr_standard
J 0
(-3225 3250);
DISPLAY 0.723404 (-3225 3250);
PAINT MONO (-3225 3250);
DISPLAY INVISIBLE (-3225 3250);
FORCEPROP 1 LAST BODY_TYPE PLUMBING
J 0
(-3225 3300);
DISPLAY 0.872340 (-3225 3300);
PAINT GREEN (-3225 3300);
DISPLAY INVISIBLE (-3225 3300);
FORCEPROP 1 LAST HDL_TAP TRUE
J 0
(-2900 3125);
DISPLAY 0.872340 (-2900 3125);
DISPLAY INVISIBLE (-2900 3125);
FORCEPROP 1 LAST PATH I229
J 0
(-3227 3250);
DISPLAY 0.872340 (-3227 3250);
PAINT GREEN (-3227 3250);
DISPLAY INVISIBLE (-3227 3250);
FORCEADD TAP..1
R 2
(-7450 3275);
FORCEPROP 3 LASTPIN (-7400 3275) SIG_NAME M_A_CPU1_SB_CB<0>
J 0
(-7390 3285);
DISPLAY 0.659574 (-7390 3285);
PAINT MONO (-7390 3285);
DISPLAY INVISIBLE (-7390 3285);
FORCEPROP 1 LASTPIN (-7400 3275) BN 0
J 2
(-7388 3283);
DISPLAY 0.489362 (-7388 3283);
PAINT GREEN (-7388 3283);
FORCEPROP 2 LAST CDS_LIB mstr_standard
J 0
(-7450 3275);
DISPLAY 0.723404 (-7450 3275);
PAINT MONO (-7450 3275);
DISPLAY INVISIBLE (-7450 3275);
FORCEPROP 1 LAST BODY_TYPE PLUMBING
J 2
(-7450 3325);
DISPLAY 0.872340 (-7450 3325);
PAINT GREEN (-7450 3325);
DISPLAY INVISIBLE (-7450 3325);
FORCEPROP 1 LAST HDL_TAP TRUE
J 2
(-7775 3150);
DISPLAY 0.872340 (-7775 3150);
DISPLAY INVISIBLE (-7775 3150);
FORCEPROP 1 LAST PATH I23
J 2
(-7448 3275);
DISPLAY 0.872340 (-7448 3275);
PAINT GREEN (-7448 3275);
DISPLAY INVISIBLE (-7448 3275);
FORCEADD TAP..1
(-3225 3050);
FORCEPROP 3 LASTPIN (-3275 3050) SIG_NAME M_A_CPU1_SB_DQS_DP<4>
J 0
(-3265 3060);
DISPLAY 0.659574 (-3265 3060);
PAINT MONO (-3265 3060);
DISPLAY INVISIBLE (-3265 3060);
FORCEPROP 1 LASTPIN (-3275 3050) BN 4
J 0
(-3287 3058);
DISPLAY 0.489362 (-3287 3058);
PAINT GREEN (-3287 3058);
FORCEPROP 2 LAST CDS_LIB mstr_standard
J 0
(-3225 3050);
DISPLAY 0.723404 (-3225 3050);
PAINT MONO (-3225 3050);
DISPLAY INVISIBLE (-3225 3050);
FORCEPROP 1 LAST BODY_TYPE PLUMBING
J 0
(-3225 3100);
DISPLAY 0.872340 (-3225 3100);
PAINT GREEN (-3225 3100);
DISPLAY INVISIBLE (-3225 3100);
FORCEPROP 1 LAST HDL_TAP TRUE
J 0
(-2900 2925);
DISPLAY 0.872340 (-2900 2925);
DISPLAY INVISIBLE (-2900 2925);
FORCEPROP 1 LAST PATH I230
J 0
(-3227 3050);
DISPLAY 0.872340 (-3227 3050);
PAINT GREEN (-3227 3050);
DISPLAY INVISIBLE (-3227 3050);
FORCEADD TAP..1
(-3225 3150);
FORCEPROP 3 LASTPIN (-3275 3150) SIG_NAME M_A_CPU1_SB_DQS_DP<5>
J 0
(-3265 3160);
DISPLAY 0.659574 (-3265 3160);
PAINT MONO (-3265 3160);
DISPLAY INVISIBLE (-3265 3160);
FORCEPROP 1 LASTPIN (-3275 3150) BN 5
J 0
(-3287 3158);
DISPLAY 0.489362 (-3287 3158);
PAINT GREEN (-3287 3158);
FORCEPROP 2 LAST CDS_LIB mstr_standard
J 0
(-3225 3150);
DISPLAY 0.723404 (-3225 3150);
PAINT MONO (-3225 3150);
DISPLAY INVISIBLE (-3225 3150);
FORCEPROP 1 LAST BODY_TYPE PLUMBING
J 0
(-3225 3200);
DISPLAY 0.872340 (-3225 3200);
PAINT GREEN (-3225 3200);
DISPLAY INVISIBLE (-3225 3200);
FORCEPROP 1 LAST HDL_TAP TRUE
J 0
(-2900 3025);
DISPLAY 0.872340 (-2900 3025);
DISPLAY INVISIBLE (-2900 3025);
FORCEPROP 1 LAST PATH I231
J 0
(-3227 3150);
DISPLAY 0.872340 (-3227 3150);
PAINT GREEN (-3227 3150);
DISPLAY INVISIBLE (-3227 3150);
FORCEADD TAP..1
(-3225 2950);
FORCEPROP 3 LASTPIN (-3275 2950) SIG_NAME M_A_CPU1_SB_DQS_DP<3>
J 0
(-3265 2960);
DISPLAY 0.659574 (-3265 2960);
PAINT MONO (-3265 2960);
DISPLAY INVISIBLE (-3265 2960);
FORCEPROP 1 LASTPIN (-3275 2950) BN 3
J 0
(-3287 2958);
DISPLAY 0.489362 (-3287 2958);
PAINT GREEN (-3287 2958);
FORCEPROP 2 LAST CDS_LIB mstr_standard
J 0
(-3225 2950);
DISPLAY 0.723404 (-3225 2950);
PAINT MONO (-3225 2950);
DISPLAY INVISIBLE (-3225 2950);
FORCEPROP 1 LAST BODY_TYPE PLUMBING
J 0
(-3225 3000);
DISPLAY 0.872340 (-3225 3000);
PAINT GREEN (-3225 3000);
DISPLAY INVISIBLE (-3225 3000);
FORCEPROP 1 LAST HDL_TAP TRUE
J 0
(-2900 2825);
DISPLAY 0.872340 (-2900 2825);
DISPLAY INVISIBLE (-2900 2825);
FORCEPROP 1 LAST PATH I232
J 0
(-3227 2950);
DISPLAY 0.872340 (-3227 2950);
PAINT GREEN (-3227 2950);
DISPLAY INVISIBLE (-3227 2950);
FORCEADD TAP..1
(-3225 2850);
FORCEPROP 3 LASTPIN (-3275 2850) SIG_NAME M_A_CPU1_SB_DQS_DP<2>
J 0
(-3265 2860);
DISPLAY 0.659574 (-3265 2860);
PAINT MONO (-3265 2860);
DISPLAY INVISIBLE (-3265 2860);
FORCEPROP 1 LASTPIN (-3275 2850) BN 2
J 0
(-3287 2858);
DISPLAY 0.489362 (-3287 2858);
PAINT GREEN (-3287 2858);
FORCEPROP 2 LAST CDS_LIB mstr_standard
J 0
(-3225 2850);
DISPLAY 0.723404 (-3225 2850);
PAINT MONO (-3225 2850);
DISPLAY INVISIBLE (-3225 2850);
FORCEPROP 1 LAST BODY_TYPE PLUMBING
J 0
(-3225 2900);
DISPLAY 0.872340 (-3225 2900);
PAINT GREEN (-3225 2900);
DISPLAY INVISIBLE (-3225 2900);
FORCEPROP 1 LAST HDL_TAP TRUE
J 0
(-2900 2725);
DISPLAY 0.872340 (-2900 2725);
DISPLAY INVISIBLE (-2900 2725);
FORCEPROP 1 LAST PATH I233
J 0
(-3227 2850);
DISPLAY 0.872340 (-3227 2850);
PAINT GREEN (-3227 2850);
DISPLAY INVISIBLE (-3227 2850);
FORCEADD TAP..1
(-3025 2700);
FORCEPROP 3 LASTPIN (-3075 2700) SIG_NAME M_A_CPU1_SB_DQS_DN<1>
J 0
(-3065 2710);
DISPLAY 0.659574 (-3065 2710);
PAINT MONO (-3065 2710);
DISPLAY INVISIBLE (-3065 2710);
FORCEPROP 1 LASTPIN (-3075 2700) BN 1
J 0
(-3087 2708);
DISPLAY 0.489362 (-3087 2708);
PAINT GREEN (-3087 2708);
FORCEPROP 2 LAST CDS_LIB mstr_standard
J 0
(-3025 2700);
DISPLAY 0.723404 (-3025 2700);
PAINT MONO (-3025 2700);
DISPLAY INVISIBLE (-3025 2700);
FORCEPROP 1 LAST BODY_TYPE PLUMBING
J 0
(-3025 2750);
DISPLAY 0.872340 (-3025 2750);
PAINT GREEN (-3025 2750);
DISPLAY INVISIBLE (-3025 2750);
FORCEPROP 1 LAST HDL_TAP TRUE
J 0
(-2700 2575);
DISPLAY 0.872340 (-2700 2575);
DISPLAY INVISIBLE (-2700 2575);
FORCEPROP 1 LAST PATH I234
J 0
(-3027 2700);
DISPLAY 0.872340 (-3027 2700);
PAINT GREEN (-3027 2700);
DISPLAY INVISIBLE (-3027 2700);
FORCEADD TAP..1
(-3025 2600);
FORCEPROP 3 LASTPIN (-3075 2600) SIG_NAME M_A_CPU1_SB_DQS_DN<0>
J 0
(-3065 2610);
DISPLAY 0.659574 (-3065 2610);
PAINT MONO (-3065 2610);
DISPLAY INVISIBLE (-3065 2610);
FORCEPROP 1 LASTPIN (-3075 2600) BN 0
J 0
(-3087 2608);
DISPLAY 0.489362 (-3087 2608);
PAINT GREEN (-3087 2608);
FORCEPROP 2 LAST CDS_LIB mstr_standard
J 0
(-3025 2600);
DISPLAY 0.723404 (-3025 2600);
PAINT MONO (-3025 2600);
DISPLAY INVISIBLE (-3025 2600);
FORCEPROP 1 LAST BODY_TYPE PLUMBING
J 0
(-3025 2650);
DISPLAY 0.872340 (-3025 2650);
PAINT GREEN (-3025 2650);
DISPLAY INVISIBLE (-3025 2650);
FORCEPROP 1 LAST HDL_TAP TRUE
J 0
(-2700 2475);
DISPLAY 0.872340 (-2700 2475);
DISPLAY INVISIBLE (-2700 2475);
FORCEPROP 1 LAST PATH I235
J 0
(-3027 2600);
DISPLAY 0.872340 (-3027 2600);
PAINT GREEN (-3027 2600);
DISPLAY INVISIBLE (-3027 2600);
FORCEADD TAP..1
(-3225 2650);
FORCEPROP 3 LASTPIN (-3275 2650) SIG_NAME M_A_CPU1_SB_DQS_DP<0>
J 0
(-3265 2660);
DISPLAY 0.659574 (-3265 2660);
PAINT MONO (-3265 2660);
DISPLAY INVISIBLE (-3265 2660);
FORCEPROP 1 LASTPIN (-3275 2650) BN 0
J 0
(-3287 2658);
DISPLAY 0.489362 (-3287 2658);
PAINT GREEN (-3287 2658);
FORCEPROP 2 LAST CDS_LIB mstr_standard
J 0
(-3225 2650);
DISPLAY 0.723404 (-3225 2650);
PAINT MONO (-3225 2650);
DISPLAY INVISIBLE (-3225 2650);
FORCEPROP 1 LAST BODY_TYPE PLUMBING
J 0
(-3225 2700);
DISPLAY 0.872340 (-3225 2700);
PAINT GREEN (-3225 2700);
DISPLAY INVISIBLE (-3225 2700);
FORCEPROP 1 LAST HDL_TAP TRUE
J 0
(-2900 2525);
DISPLAY 0.872340 (-2900 2525);
DISPLAY INVISIBLE (-2900 2525);
FORCEPROP 1 LAST PATH I236
J 0
(-3227 2650);
DISPLAY 0.872340 (-3227 2650);
PAINT GREEN (-3227 2650);
DISPLAY INVISIBLE (-3227 2650);
FORCEADD TAP..1
(-3225 2750);
FORCEPROP 3 LASTPIN (-3275 2750) SIG_NAME M_A_CPU1_SB_DQS_DP<1>
J 0
(-3265 2760);
DISPLAY 0.659574 (-3265 2760);
PAINT MONO (-3265 2760);
DISPLAY INVISIBLE (-3265 2760);
FORCEPROP 1 LASTPIN (-3275 2750) BN 1
J 0
(-3287 2758);
DISPLAY 0.489362 (-3287 2758);
PAINT GREEN (-3287 2758);
FORCEPROP 2 LAST CDS_LIB mstr_standard
J 0
(-3225 2750);
DISPLAY 0.723404 (-3225 2750);
PAINT MONO (-3225 2750);
DISPLAY INVISIBLE (-3225 2750);
FORCEPROP 1 LAST BODY_TYPE PLUMBING
J 0
(-3225 2800);
DISPLAY 0.872340 (-3225 2800);
PAINT GREEN (-3225 2800);
DISPLAY INVISIBLE (-3225 2800);
FORCEPROP 1 LAST HDL_TAP TRUE
J 0
(-2900 2625);
DISPLAY 0.872340 (-2900 2625);
DISPLAY INVISIBLE (-2900 2625);
FORCEPROP 1 LAST PATH I237
J 0
(-3227 2750);
DISPLAY 0.872340 (-3227 2750);
PAINT GREEN (-3227 2750);
DISPLAY INVISIBLE (-3227 2750);
FORCEADD SCONN288_DDR506112002KQ..2
(-4225 3600);
FORCEPROP 1 LAST LOCATION J24
J 0
(-4825 4925);
DISPLAY 0.468085 (-4825 4925);
PAINT SKYBLUE (-4825 4925);
FORCEPROP 0 LAST $SEC 2
J 0
(-4675 5075);
DISPLAY 0.680851 (-4675 5075);
PAINT MONO (-4675 5075);
DISPLAY INVISIBLE (-4675 5075);
FORCEPROP 2 LAST CDS_SEC 2
J 0
(-4675 5075);
DISPLAY 0.680851 (-4675 5075);
DISPLAY INVISIBLE (-4675 5075);
FORCEPROP 0 LASTPIN (-3475 3650) $PN 12
J 0
(-3465 3660);
DISPLAY 0.680851 (-3465 3660);
PAINT MONO (-3465 3660);
FORCEPROP 0 LASTPIN (-3475 3700) $PN 11
J 0
(-3465 3710);
DISPLAY 0.680851 (-3465 3710);
PAINT MONO (-3465 3710);
FORCEPROP 0 LASTPIN (-3475 2600) $PN 105
J 0
(-3465 2610);
DISPLAY 0.680851 (-3465 2610);
PAINT MONO (-3465 2610);
FORCEPROP 0 LASTPIN (-3475 2650) $PN 104
J 0
(-3465 2660);
DISPLAY 0.680851 (-3465 2660);
PAINT MONO (-3465 2660);
FORCEPROP 0 LASTPIN (-3475 3750) $PN 23
J 0
(-3465 3760);
DISPLAY 0.680851 (-3465 3760);
PAINT MONO (-3465 3760);
FORCEPROP 0 LASTPIN (-3475 3800) $PN 22
J 0
(-3465 3810);
DISPLAY 0.680851 (-3465 3810);
PAINT MONO (-3465 3810);
FORCEPROP 0 LASTPIN (-3475 2700) $PN 116
J 0
(-3465 2710);
DISPLAY 0.680851 (-3465 2710);
PAINT MONO (-3465 2710);
FORCEPROP 0 LASTPIN (-3475 2750) $PN 115
J 0
(-3465 2760);
DISPLAY 0.680851 (-3465 2760);
PAINT MONO (-3465 2760);
FORCEPROP 0 LASTPIN (-3475 3850) $PN 34
J 0
(-3465 3860);
DISPLAY 0.680851 (-3465 3860);
PAINT MONO (-3465 3860);
FORCEPROP 0 LASTPIN (-3475 3900) $PN 33
J 0
(-3465 3910);
DISPLAY 0.680851 (-3465 3910);
PAINT MONO (-3465 3910);
FORCEPROP 0 LASTPIN (-3475 2800) $PN 127
J 0
(-3465 2810);
DISPLAY 0.680851 (-3465 2810);
PAINT MONO (-3465 2810);
FORCEPROP 0 LASTPIN (-3475 2850) $PN 126
J 0
(-3465 2860);
DISPLAY 0.680851 (-3465 2860);
PAINT MONO (-3465 2860);
FORCEPROP 0 LASTPIN (-3475 3950) $PN 45
J 0
(-3465 3960);
DISPLAY 0.680851 (-3465 3960);
PAINT MONO (-3465 3960);
FORCEPROP 0 LASTPIN (-3475 4000) $PN 44
J 0
(-3465 4010);
DISPLAY 0.680851 (-3465 4010);
PAINT MONO (-3465 4010);
FORCEPROP 0 LASTPIN (-3475 2900) $PN 138
J 0
(-3465 2910);
DISPLAY 0.680851 (-3465 2910);
PAINT MONO (-3465 2910);
FORCEPROP 0 LASTPIN (-3475 2950) $PN 137
J 0
(-3465 2960);
DISPLAY 0.680851 (-3465 2960);
PAINT MONO (-3465 2960);
FORCEPROP 0 LASTPIN (-3475 4050) $PN 56
J 0
(-3465 4060);
DISPLAY 0.680851 (-3465 4060);
PAINT MONO (-3465 4060);
FORCEPROP 0 LASTPIN (-3475 4100) $PN 55
J 0
(-3465 4110);
DISPLAY 0.680851 (-3465 4110);
PAINT MONO (-3465 4110);
FORCEPROP 0 LASTPIN (-3475 3000) $PN 238
J 0
(-3465 3010);
DISPLAY 0.680851 (-3465 3010);
PAINT MONO (-3465 3010);
FORCEPROP 0 LASTPIN (-3475 3050) $PN 239
J 0
(-3465 3060);
DISPLAY 0.680851 (-3465 3060);
PAINT MONO (-3465 3060);
FORCEPROP 0 LASTPIN (-3475 4150) $PN 156
J 0
(-3465 4160);
DISPLAY 0.680851 (-3465 4160);
PAINT MONO (-3465 4160);
FORCEPROP 0 LASTPIN (-3475 4200) $PN 157
J 0
(-3465 4210);
DISPLAY 0.680851 (-3465 4210);
PAINT MONO (-3465 4210);
FORCEPROP 0 LASTPIN (-3475 3100) $PN 249
J 0
(-3465 3110);
DISPLAY 0.680851 (-3465 3110);
PAINT MONO (-3465 3110);
FORCEPROP 0 LASTPIN (-3475 3150) $PN 250
J 0
(-3465 3160);
DISPLAY 0.680851 (-3465 3160);
PAINT MONO (-3465 3160);
FORCEPROP 0 LASTPIN (-3475 4250) $PN 167
J 0
(-3465 4260);
DISPLAY 0.680851 (-3465 4260);
PAINT MONO (-3465 4260);
FORCEPROP 0 LASTPIN (-3475 4300) $PN 168
J 0
(-3465 4310);
DISPLAY 0.680851 (-3465 4310);
PAINT MONO (-3465 4310);
FORCEPROP 0 LASTPIN (-3475 3200) $PN 260
J 0
(-3465 3210);
DISPLAY 0.680851 (-3465 3210);
PAINT MONO (-3465 3210);
FORCEPROP 0 LASTPIN (-3475 3250) $PN 261
J 0
(-3465 3260);
DISPLAY 0.680851 (-3465 3260);
PAINT MONO (-3465 3260);
FORCEPROP 0 LASTPIN (-3475 4350) $PN 178
J 0
(-3465 4360);
DISPLAY 0.680851 (-3465 4360);
PAINT MONO (-3465 4360);
FORCEPROP 0 LASTPIN (-3475 4400) $PN 179
J 0
(-3465 4410);
DISPLAY 0.680851 (-3465 4410);
PAINT MONO (-3465 4410);
FORCEPROP 0 LASTPIN (-3475 3300) $PN 271
J 0
(-3465 3310);
DISPLAY 0.680851 (-3465 3310);
PAINT MONO (-3465 3310);
FORCEPROP 0 LASTPIN (-3475 3350) $PN 272
J 0
(-3465 3360);
DISPLAY 0.680851 (-3465 3360);
PAINT MONO (-3465 3360);
FORCEPROP 0 LASTPIN (-3475 4450) $PN 189
J 0
(-3465 4460);
DISPLAY 0.680851 (-3465 4460);
PAINT MONO (-3465 4460);
FORCEPROP 0 LASTPIN (-3475 4500) $PN 190
J 0
(-3465 4510);
DISPLAY 0.680851 (-3465 4510);
PAINT MONO (-3465 4510);
FORCEPROP 0 LASTPIN (-3475 3400) $PN 282
J 0
(-3465 3410);
DISPLAY 0.680851 (-3465 3410);
PAINT MONO (-3465 3410);
FORCEPROP 0 LASTPIN (-3475 3450) $PN 283
J 0
(-3465 3460);
DISPLAY 0.680851 (-3465 3460);
PAINT MONO (-3465 3460);
FORCEPROP 0 LASTPIN (-3475 4550) $PN 200
J 0
(-3465 4560);
DISPLAY 0.680851 (-3465 4560);
PAINT MONO (-3465 4560);
FORCEPROP 0 LASTPIN (-3475 4600) $PN 201
J 0
(-3465 4610);
DISPLAY 0.680851 (-3465 4610);
PAINT MONO (-3465 4610);
FORCEPROP 0 LASTPIN (-3475 3500) $PN 94
J 0
(-3465 3510);
DISPLAY 0.680851 (-3465 3510);
PAINT MONO (-3465 3510);
FORCEPROP 0 LASTPIN (-3475 3550) $PN 93
J 0
(-3465 3560);
DISPLAY 0.680851 (-3465 3560);
PAINT MONO (-3465 3560);
FORCEPROP 2 LAST PART_TYPE SMLF
J 0
(-4675 5025);
DISPLAY 1.021277 (-4675 5025);
FORCEPROP 2 LAST VALUE SCONN288_DDR506112002KQ
J 0
(-4675 4975);
DISPLAY 0.489362 (-4675 4975);
PAINT SKYBLUE (-4675 4975);
FORCEPROP 1 LAST PART_NUMBER DFHST8FS479
J 0
(-4825 4850);
DISPLAY 0.468085 (-4825 4850);
PAINT SKYBLUE (-4825 4850);
FORCEPROP 1 LAST MATERIAL IO
J 0
(-4825 4775);
DISPLAY 0.468085 (-4825 4775);
PAINT SKYBLUE (-4825 4775);
FORCEPROP 1 LAST CDS_LMAN_SYM_OUTLINE -600,1150,600,-1150
J 0
(-4225 3600);
DISPLAY 0.468085 (-4225 3600);
PAINT GREEN (-4225 3600);
DISPLAY INVISIBLE (-4225 3600);
FORCEPROP 1 LAST PATH I238
J 0
(-4225 3600);
DISPLAY 0.723404 (-4225 3600);
PAINT GREEN (-4225 3600);
DISPLAY INVISIBLE (-4225 3600);
FORCEPROP 1 LAST NEEDS_NO_SIZE TRUE
J 0
(-4225 3600);
DISPLAY 0.723404 (-4225 3600);
PAINT GREEN (-4225 3600);
DISPLAY INVISIBLE (-4225 3600);
FORCEPROP 2 LAST CDS_LIB pure_quanta
J 0
(-4225 3600);
DISPLAY INVISIBLE (-4225 3600);
FORCEADD GND..1
(-2800 5750);
FORCEPROP 3 LASTPIN (-2800 5800) SIG_NAME GND\g
J 0
(-2790 5810);
DISPLAY 0.659574 (-2790 5810);
PAINT MONO (-2790 5810);
DISPLAY INVISIBLE (-2790 5810);
FORCEPROP 2 LAST CDS_LIB pure_quanta_power
J 0
(-2800 5750);
DISPLAY INVISIBLE (-2800 5750);
FORCEPROP 2 LAST BOM_COST MEM
J 0
(-2775 5875);
DISPLAY 0.659574 (-2775 5875);
DISPLAY INVISIBLE (-2775 5875);
FORCEPROP 1 LAST SIZE 1B
J 0
(-2725 5700);
DISPLAY 0.723404 (-2725 5700);
PAINT GREEN (-2725 5700);
DISPLAY INVISIBLE (-2725 5700);
FORCEPROP 1 LAST PATH I239
J 0
(-2725 5750);
DISPLAY 0.872340 (-2725 5750);
PAINT AQUA (-2725 5750);
DISPLAY INVISIBLE (-2725 5750);
FORCEPROP 2 LAST ROOM MEM_EFGH_DECOUPLING_CAPS
J 0
(-2775 5825);
DISPLAY 0.659574 (-2775 5825);
PAINT RED (-2775 5825);
DISPLAY INVISIBLE (-2775 5825);
FORCEPROP 1 LAST HDL_POWER GND
J 0
(-2800 5900);
DISPLAY 0.723404 (-2800 5900);
PAINT GREEN (-2800 5900);
DISPLAY INVISIBLE (-2800 5900);
FORCEADD TAP..1
R 2
(-7450 3325);
FORCEPROP 3 LASTPIN (-7400 3325) SIG_NAME M_A_CPU1_SB_CB<1>
J 0
(-7390 3335);
DISPLAY 0.659574 (-7390 3335);
PAINT MONO (-7390 3335);
DISPLAY INVISIBLE (-7390 3335);
FORCEPROP 1 LASTPIN (-7400 3325) BN 1
J 2
(-7388 3333);
DISPLAY 0.489362 (-7388 3333);
PAINT GREEN (-7388 3333);
FORCEPROP 2 LAST CDS_LIB mstr_standard
J 0
(-7450 3325);
DISPLAY 0.723404 (-7450 3325);
PAINT MONO (-7450 3325);
DISPLAY INVISIBLE (-7450 3325);
FORCEPROP 1 LAST BODY_TYPE PLUMBING
J 2
(-7450 3375);
DISPLAY 0.872340 (-7450 3375);
PAINT GREEN (-7450 3375);
DISPLAY INVISIBLE (-7450 3375);
FORCEPROP 1 LAST HDL_TAP TRUE
J 2
(-7775 3200);
DISPLAY 0.872340 (-7775 3200);
DISPLAY INVISIBLE (-7775 3200);
FORCEPROP 1 LAST PATH I24
J 2
(-7448 3325);
DISPLAY 0.872340 (-7448 3325);
PAINT GREEN (-7448 3325);
DISPLAY INVISIBLE (-7448 3325);
FORCEADD Q_CAP..1
R 2
(-2800 6100);
FORCEPROP 1 LAST LOCATION C173
J 2
(-2850 6200);
DISPLAY 0.489362 (-2850 6200);
PAINT SKYBLUE (-2850 6200);
FORCEPROP 0 LAST $SEC 1
J 0
(-2850 6250);
DISPLAY 0.680851 (-2850 6250);
PAINT MONO (-2850 6250);
DISPLAY INVISIBLE (-2850 6250);
FORCEPROP 0 LAST CDS_SEC 1
J 0
(-2850 6250);
DISPLAY 0.680851 (-2850 6250);
DISPLAY INVISIBLE (-2850 6250);
FORCEPROP 1 LASTPIN (-2800 6200) $PN 1
J 2
(-2810 6180);
DISPLAY 0.489362 (-2810 6180);
PAINT MONO (-2810 6180);
FORCEPROP 1 LASTPIN (-2800 6000) $PN 2
J 2
(-2810 5980);
DISPLAY 0.489362 (-2810 5980);
PAINT MONO (-2810 5980);
FORCEPROP 1 LAST MATERIAL X6S
J 2
(-2850 6000);
DISPLAY 0.489362 (-2850 6000);
PAINT SKYBLUE (-2850 6000);
FORCEPROP 1 LAST TOLERANCE 10%
J 2
(-2850 6050);
DISPLAY 0.489362 (-2850 6050);
PAINT SKYBLUE (-2850 6050);
FORCEPROP 1 LAST VALUE 10UF
J 2
(-2850 6150);
DISPLAY 0.489362 (-2850 6150);
PAINT SKYBLUE (-2850 6150);
FORCEPROP 1 LAST PART_NUMBER CH6104KEA00
J 2
(-2850 5950);
DISPLAY 0.489362 (-2850 5950);
PAINT SKYBLUE (-2850 5950);
FORCEPROP 1 LAST VOLTAGE 25V
J 2
(-2850 6100);
DISPLAY 0.489362 (-2850 6100);
PAINT SKYBLUE (-2850 6100);
FORCEPROP 1 LAST PACK_TYPE C0805
J 2
(-2850 5900);
DISPLAY 0.489362 (-2850 5900);
PAINT SKYBLUE (-2850 5900);
FORCEPROP 0 LAST BOM_COST MEM
J 2
(-2855 6245);
DISPLAY 0.595745 (-2855 6245);
PAINT MONO (-2855 6245);
DISPLAY INVISIBLE (-2855 6245);
FORCEPROP 2 LAST CDS_LIB pure_quanta
J 0
(-2800 6100);
DISPLAY INVISIBLE (-2800 6100);
FORCEPROP 1 LAST PATH I240
J 2
(-2850 6250);
DISPLAY 0.978723 (-2850 6250);
PAINT WHITE (-2850 6250);
DISPLAY INVISIBLE (-2850 6250);
FORCEPROP 0 LAST ROOM MEM_CH_A_CPU0_DIMM1
J 2
(-2855 6245);
DISPLAY 0.595745 (-2855 6245);
PAINT RED (-2855 6245);
DISPLAY INVISIBLE (-2855 6245);
FORCEADD Q_CAP..1
R 2
(-2225 6100);
FORCEPROP 1 LAST LOCATION C174
J 2
(-2275 6200);
DISPLAY 0.489362 (-2275 6200);
PAINT SKYBLUE (-2275 6200);
FORCEPROP 0 LAST $SEC 1
J 0
(-2275 6250);
DISPLAY 0.680851 (-2275 6250);
PAINT MONO (-2275 6250);
DISPLAY INVISIBLE (-2275 6250);
FORCEPROP 0 LAST CDS_SEC 1
J 0
(-2275 6250);
DISPLAY 0.680851 (-2275 6250);
DISPLAY INVISIBLE (-2275 6250);
FORCEPROP 1 LASTPIN (-2225 6200) $PN 1
J 2
(-2235 6180);
DISPLAY 0.489362 (-2235 6180);
PAINT MONO (-2235 6180);
FORCEPROP 1 LASTPIN (-2225 6000) $PN 2
J 2
(-2235 5980);
DISPLAY 0.489362 (-2235 5980);
PAINT MONO (-2235 5980);
FORCEPROP 1 LAST MATERIAL X6S
J 2
(-2275 6000);
DISPLAY 0.489362 (-2275 6000);
PAINT SKYBLUE (-2275 6000);
FORCEPROP 1 LAST TOLERANCE 10%
J 2
(-2275 6050);
DISPLAY 0.489362 (-2275 6050);
PAINT SKYBLUE (-2275 6050);
FORCEPROP 1 LAST VALUE 10UF
J 2
(-2275 6150);
DISPLAY 0.489362 (-2275 6150);
PAINT SKYBLUE (-2275 6150);
FORCEPROP 1 LAST PART_NUMBER CH6104KEA00
J 2
(-2275 5950);
DISPLAY 0.489362 (-2275 5950);
PAINT SKYBLUE (-2275 5950);
FORCEPROP 1 LAST VOLTAGE 25V
J 2
(-2275 6100);
DISPLAY 0.489362 (-2275 6100);
PAINT SKYBLUE (-2275 6100);
FORCEPROP 1 LAST PACK_TYPE C0805
J 2
(-2275 5900);
DISPLAY 0.489362 (-2275 5900);
PAINT SKYBLUE (-2275 5900);
FORCEPROP 0 LAST BOM_COST MEM
J 2
(-2280 6245);
DISPLAY 0.595745 (-2280 6245);
PAINT MONO (-2280 6245);
DISPLAY INVISIBLE (-2280 6245);
FORCEPROP 2 LAST CDS_LIB pure_quanta
J 0
(-2225 6100);
DISPLAY INVISIBLE (-2225 6100);
FORCEPROP 1 LAST PATH I241
J 2
(-2275 6250);
DISPLAY 0.978723 (-2275 6250);
PAINT WHITE (-2275 6250);
DISPLAY INVISIBLE (-2275 6250);
FORCEPROP 0 LAST ROOM MEM_CH_A_CPU0_DIMM1
J 2
(-2280 6245);
DISPLAY 0.595745 (-2280 6245);
PAINT RED (-2280 6245);
DISPLAY INVISIBLE (-2280 6245);
FORCEADD UNIVERSAL_POWER..1
(-2800 6425);
FORCEPROP 3 LASTPIN (-2800 6375) SIG_NAME P12V_MEM_2\g
J 0
(-2790 6385);
DISPLAY 0.659574 (-2790 6385);
PAINT MONO (-2790 6385);
DISPLAY INVISIBLE (-2790 6385);
FORCEPROP 1 LAST HDL_POWER P12V_MEM_2
J 1
(-2800 6475);
DISPLAY 0.489362 (-2800 6475);
PAINT GREEN (-2800 6475);
FORCEPROP 2 LAST CDS_LIB pure_quanta_power
J 0
(-2800 6425);
DISPLAY INVISIBLE (-2800 6425);
FORCEPROP 1 LAST PATH I242
J 0
(-2750 6450);
DISPLAY 0.872340 (-2750 6450);
PAINT AQUA (-2750 6450);
DISPLAY INVISIBLE (-2750 6450);
FORCEADD OFFPAGE..1
(-8075 2775);
FORCEPROP 2 LAST $XR5 102 
J 0
(-8867 2775);
DISPLAY 0.638298 (-8867 2775);
PAINT MONO (-8867 2775);
FORCEPROP 2 LAST $XR4 101 
J 0
(-8747 2775);
DISPLAY 0.638298 (-8747 2775);
PAINT MONO (-8747 2775);
FORCEPROP 2 LAST $XR3 100 
J 0
(-8627 2775);
DISPLAY 0.638298 (-8627 2775);
PAINT MONO (-8627 2775);
FORCEPROP 2 LAST $XR2 99 
J 0
(-8507 2775);
DISPLAY 0.638298 (-8507 2775);
PAINT MONO (-8507 2775);
FORCEPROP 2 LAST $XR1 98 
J 0
(-8417 2775);
DISPLAY 0.638298 (-8417 2775);
PAINT MONO (-8417 2775);
FORCEPROP 2 LAST $XR0 136 
J 0
(-8327 2775);
DISPLAY 0.638298 (-8327 2775);
PAINT MONO (-8327 2775);
FORCEPROP 2 LAST PATH I243
J 0
(-8375 2825);
DISPLAY 0.680851 (-8375 2825);
DISPLAY INVISIBLE (-8375 2825);
FORCEPROP 2 LAST CDS_LIB mstr_standard
J 0
(-8075 2775);
DISPLAY 0.808511 (-8075 2775);
DISPLAY INVISIBLE (-8075 2775);
FORCEPROP 1 LAST OFFPAGE TRUE
J 0
(-7750 2650);
DISPLAY 0.872340 (-7750 2650);
PAINT GREEN (-7750 2650);
DISPLAY INVISIBLE (-7750 2650);
FORCEPROP 1 LAST COMMENT_BODY TRUE
J 0
(-7950 2675);
DISPLAY 0.872340 (-7950 2675);
PAINT GREEN (-7950 2675);
DISPLAY INVISIBLE (-7950 2675);
FORCEADD Q_RES..1
(-7500 2775);
FORCEPROP 1 LAST $LOCATION R1580
J 0
(-7550 2800);
DISPLAY 0.510638 (-7550 2800);
PAINT SKYBLUE (-7550 2800);
FORCEPROP 0 LAST CDS_LOCATION R1580
J 0
(-7550 2875);
DISPLAY 0.680851 (-7550 2875);
DISPLAY INVISIBLE (-7550 2875);
FORCEPROP 0 LAST $SEC 1
J 0
(-7550 2875);
DISPLAY 0.680851 (-7550 2875);
PAINT MONO (-7550 2875);
DISPLAY INVISIBLE (-7550 2875);
FORCEPROP 0 LAST CDS_SEC 1
J 0
(-7550 2875);
DISPLAY 0.680851 (-7550 2875);
DISPLAY INVISIBLE (-7550 2875);
FORCEPROP 1 LASTPIN (-7600 2775) $PN 1
J 0
(-7588 2787);
DISPLAY 0.787234 (-7588 2787);
PAINT MONO (-7588 2787);
FORCEPROP 1 LASTPIN (-7400 2775) $PN 2
J 0
(-7438 2787);
DISPLAY 0.787234 (-7438 2787);
PAINT MONO (-7438 2787);
FORCEPROP 1 LAST VALUE 49.9
J 2
(-7350 2825);
DISPLAY 0.510638 (-7350 2825);
PAINT SKYBLUE (-7350 2825);
FORCEPROP 2 LAST CDS_LIB pure_quanta
J 0
(-7500 2775);
DISPLAY INVISIBLE (-7500 2775);
FORCEPROP 1 LAST PATH I244
J 0
(-7550 2925);
DISPLAY 0.978723 (-7550 2925);
PAINT WHITE (-7550 2925);
DISPLAY INVISIBLE (-7550 2925);
FORCEPROP 1 LAST PART_NUMBER CS04992FB07
J 0
(-7550 2875);
DISPLAY 0.978723 (-7550 2875);
DISPLAY INVISIBLE (-7550 2875);
FORCEPROP 1 LAST TOLERANCE 1%
J 0
(-7500 2675);
DISPLAY 0.978723 (-7500 2675);
DISPLAY INVISIBLE (-7500 2675);
FORCEPROP 1 LAST WATTAGE 1/16W
J 2
(-7525 2625);
DISPLAY 0.978723 (-7525 2625);
DISPLAY INVISIBLE (-7525 2625);
FORCEPROP 1 LAST PACK_TYPE 0402LF
J 0
(-7250 2625);
DISPLAY 0.978723 (-7250 2625);
DISPLAY INVISIBLE (-7250 2625);
FORCEPROP 1 LAST MATERIAL CHIP
J 0
(-7500 2625);
DISPLAY 0.978723 (-7500 2625);
DISPLAY INVISIBLE (-7500 2625);
FORCEADD TAP..1
R 2
(-7450 3375);
FORCEPROP 3 LASTPIN (-7400 3375) SIG_NAME M_A_CPU1_SB_CB<2>
J 0
(-7390 3385);
DISPLAY 0.659574 (-7390 3385);
PAINT MONO (-7390 3385);
DISPLAY INVISIBLE (-7390 3385);
FORCEPROP 1 LASTPIN (-7400 3375) BN 2
J 2
(-7388 3383);
DISPLAY 0.489362 (-7388 3383);
PAINT GREEN (-7388 3383);
FORCEPROP 2 LAST CDS_LIB mstr_standard
J 0
(-7450 3375);
DISPLAY 0.723404 (-7450 3375);
PAINT MONO (-7450 3375);
DISPLAY INVISIBLE (-7450 3375);
FORCEPROP 1 LAST BODY_TYPE PLUMBING
J 2
(-7450 3425);
DISPLAY 0.872340 (-7450 3425);
PAINT GREEN (-7450 3425);
DISPLAY INVISIBLE (-7450 3425);
FORCEPROP 1 LAST HDL_TAP TRUE
J 2
(-7775 3250);
DISPLAY 0.872340 (-7775 3250);
DISPLAY INVISIBLE (-7775 3250);
FORCEPROP 1 LAST PATH I25
J 2
(-7448 3375);
DISPLAY 0.872340 (-7448 3375);
PAINT GREEN (-7448 3375);
DISPLAY INVISIBLE (-7448 3375);
FORCEADD TAP..1
R 2
(-7450 3425);
FORCEPROP 3 LASTPIN (-7400 3425) SIG_NAME M_A_CPU1_SB_CB<3>
J 0
(-7390 3435);
DISPLAY 0.659574 (-7390 3435);
PAINT MONO (-7390 3435);
DISPLAY INVISIBLE (-7390 3435);
FORCEPROP 1 LASTPIN (-7400 3425) BN 3
J 2
(-7388 3433);
DISPLAY 0.489362 (-7388 3433);
PAINT GREEN (-7388 3433);
FORCEPROP 2 LAST CDS_LIB mstr_standard
J 0
(-7450 3425);
DISPLAY 0.723404 (-7450 3425);
PAINT MONO (-7450 3425);
DISPLAY INVISIBLE (-7450 3425);
FORCEPROP 1 LAST BODY_TYPE PLUMBING
J 2
(-7450 3475);
DISPLAY 0.872340 (-7450 3475);
PAINT GREEN (-7450 3475);
DISPLAY INVISIBLE (-7450 3475);
FORCEPROP 1 LAST HDL_TAP TRUE
J 2
(-7775 3300);
DISPLAY 0.872340 (-7775 3300);
DISPLAY INVISIBLE (-7775 3300);
FORCEPROP 1 LAST PATH I26
J 2
(-7448 3425);
DISPLAY 0.872340 (-7448 3425);
PAINT GREEN (-7448 3425);
DISPLAY INVISIBLE (-7448 3425);
FORCEADD TAP..1
R 2
(-7450 3475);
FORCEPROP 3 LASTPIN (-7400 3475) SIG_NAME M_A_CPU1_SB_CB<4>
J 0
(-7390 3485);
DISPLAY 0.659574 (-7390 3485);
PAINT MONO (-7390 3485);
DISPLAY INVISIBLE (-7390 3485);
FORCEPROP 1 LASTPIN (-7400 3475) BN 4
J 2
(-7388 3483);
DISPLAY 0.489362 (-7388 3483);
PAINT GREEN (-7388 3483);
FORCEPROP 2 LAST CDS_LIB mstr_standard
J 0
(-7450 3475);
DISPLAY 0.723404 (-7450 3475);
PAINT MONO (-7450 3475);
DISPLAY INVISIBLE (-7450 3475);
FORCEPROP 1 LAST BODY_TYPE PLUMBING
J 2
(-7450 3525);
DISPLAY 0.872340 (-7450 3525);
PAINT GREEN (-7450 3525);
DISPLAY INVISIBLE (-7450 3525);
FORCEPROP 1 LAST HDL_TAP TRUE
J 2
(-7775 3350);
DISPLAY 0.872340 (-7775 3350);
DISPLAY INVISIBLE (-7775 3350);
FORCEPROP 1 LAST PATH I27
J 2
(-7448 3475);
DISPLAY 0.872340 (-7448 3475);
PAINT GREEN (-7448 3475);
DISPLAY INVISIBLE (-7448 3475);
FORCEADD TAP..1
R 2
(-7450 3525);
FORCEPROP 3 LASTPIN (-7400 3525) SIG_NAME M_A_CPU1_SB_CB<5>
J 0
(-7390 3535);
DISPLAY 0.659574 (-7390 3535);
PAINT MONO (-7390 3535);
DISPLAY INVISIBLE (-7390 3535);
FORCEPROP 1 LASTPIN (-7400 3525) BN 5
J 2
(-7388 3533);
DISPLAY 0.489362 (-7388 3533);
PAINT GREEN (-7388 3533);
FORCEPROP 2 LAST CDS_LIB mstr_standard
J 0
(-7450 3525);
DISPLAY 0.723404 (-7450 3525);
PAINT MONO (-7450 3525);
DISPLAY INVISIBLE (-7450 3525);
FORCEPROP 1 LAST BODY_TYPE PLUMBING
J 2
(-7450 3575);
DISPLAY 0.872340 (-7450 3575);
PAINT GREEN (-7450 3575);
DISPLAY INVISIBLE (-7450 3575);
FORCEPROP 1 LAST HDL_TAP TRUE
J 2
(-7775 3400);
DISPLAY 0.872340 (-7775 3400);
DISPLAY INVISIBLE (-7775 3400);
FORCEPROP 1 LAST PATH I28
J 2
(-7448 3525);
DISPLAY 0.872340 (-7448 3525);
PAINT GREEN (-7448 3525);
DISPLAY INVISIBLE (-7448 3525);
FORCEADD TAP..1
R 2
(-7450 3575);
FORCEPROP 3 LASTPIN (-7400 3575) SIG_NAME M_A_CPU1_SB_CB<6>
J 0
(-7390 3585);
DISPLAY 0.659574 (-7390 3585);
PAINT MONO (-7390 3585);
DISPLAY INVISIBLE (-7390 3585);
FORCEPROP 1 LASTPIN (-7400 3575) BN 6
J 2
(-7388 3583);
DISPLAY 0.489362 (-7388 3583);
PAINT GREEN (-7388 3583);
FORCEPROP 2 LAST CDS_LIB mstr_standard
J 0
(-7450 3575);
DISPLAY 0.723404 (-7450 3575);
PAINT MONO (-7450 3575);
DISPLAY INVISIBLE (-7450 3575);
FORCEPROP 1 LAST BODY_TYPE PLUMBING
J 2
(-7450 3625);
DISPLAY 0.872340 (-7450 3625);
PAINT GREEN (-7450 3625);
DISPLAY INVISIBLE (-7450 3625);
FORCEPROP 1 LAST HDL_TAP TRUE
J 2
(-7775 3450);
DISPLAY 0.872340 (-7775 3450);
DISPLAY INVISIBLE (-7775 3450);
FORCEPROP 1 LAST PATH I29
J 2
(-7448 3575);
DISPLAY 0.872340 (-7448 3575);
PAINT GREEN (-7448 3575);
DISPLAY INVISIBLE (-7448 3575);
FORCEADD TAP..1
R 2
(-7450 3625);
FORCEPROP 3 LASTPIN (-7400 3625) SIG_NAME M_A_CPU1_SB_CB<7>
J 0
(-7390 3635);
DISPLAY 0.659574 (-7390 3635);
PAINT MONO (-7390 3635);
DISPLAY INVISIBLE (-7390 3635);
FORCEPROP 1 LASTPIN (-7400 3625) BN 7
J 2
(-7388 3633);
DISPLAY 0.489362 (-7388 3633);
PAINT GREEN (-7388 3633);
FORCEPROP 2 LAST CDS_LIB mstr_standard
J 0
(-7450 3625);
DISPLAY 0.723404 (-7450 3625);
PAINT MONO (-7450 3625);
DISPLAY INVISIBLE (-7450 3625);
FORCEPROP 1 LAST BODY_TYPE PLUMBING
J 2
(-7450 3675);
DISPLAY 0.872340 (-7450 3675);
PAINT GREEN (-7450 3675);
DISPLAY INVISIBLE (-7450 3675);
FORCEPROP 1 LAST HDL_TAP TRUE
J 2
(-7775 3500);
DISPLAY 0.872340 (-7775 3500);
DISPLAY INVISIBLE (-7775 3500);
FORCEPROP 1 LAST PATH I30
J 2
(-7448 3625);
DISPLAY 0.872340 (-7448 3625);
PAINT GREEN (-7448 3625);
DISPLAY INVISIBLE (-7448 3625);
FORCEADD TAP..1
R 2
(-7450 3725);
FORCEPROP 3 LASTPIN (-7400 3725) SIG_NAME M_A_CPU1_SA_CB<0>
J 0
(-7390 3735);
DISPLAY 0.659574 (-7390 3735);
PAINT MONO (-7390 3735);
DISPLAY INVISIBLE (-7390 3735);
FORCEPROP 1 LASTPIN (-7400 3725) BN 0
J 2
(-7388 3733);
DISPLAY 0.489362 (-7388 3733);
PAINT GREEN (-7388 3733);
FORCEPROP 2 LAST CDS_LIB mstr_standard
J 0
(-7450 3725);
DISPLAY 0.723404 (-7450 3725);
PAINT MONO (-7450 3725);
DISPLAY INVISIBLE (-7450 3725);
FORCEPROP 1 LAST BODY_TYPE PLUMBING
J 2
(-7450 3775);
DISPLAY 0.872340 (-7450 3775);
PAINT GREEN (-7450 3775);
DISPLAY INVISIBLE (-7450 3775);
FORCEPROP 1 LAST HDL_TAP TRUE
J 2
(-7775 3600);
DISPLAY 0.872340 (-7775 3600);
DISPLAY INVISIBLE (-7775 3600);
FORCEPROP 1 LAST PATH I31
J 2
(-7448 3725);
DISPLAY 0.872340 (-7448 3725);
PAINT GREEN (-7448 3725);
DISPLAY INVISIBLE (-7448 3725);
FORCEADD TAP..1
R 2
(-7450 3775);
FORCEPROP 3 LASTPIN (-7400 3775) SIG_NAME M_A_CPU1_SA_CB<1>
J 0
(-7390 3785);
DISPLAY 0.659574 (-7390 3785);
PAINT MONO (-7390 3785);
DISPLAY INVISIBLE (-7390 3785);
FORCEPROP 1 LASTPIN (-7400 3775) BN 1
J 2
(-7388 3783);
DISPLAY 0.489362 (-7388 3783);
PAINT GREEN (-7388 3783);
FORCEPROP 2 LAST CDS_LIB mstr_standard
J 0
(-7450 3775);
DISPLAY 0.723404 (-7450 3775);
PAINT MONO (-7450 3775);
DISPLAY INVISIBLE (-7450 3775);
FORCEPROP 1 LAST BODY_TYPE PLUMBING
J 2
(-7450 3825);
DISPLAY 0.872340 (-7450 3825);
PAINT GREEN (-7450 3825);
DISPLAY INVISIBLE (-7450 3825);
FORCEPROP 1 LAST HDL_TAP TRUE
J 2
(-7775 3650);
DISPLAY 0.872340 (-7775 3650);
DISPLAY INVISIBLE (-7775 3650);
FORCEPROP 1 LAST PATH I32
J 2
(-7448 3775);
DISPLAY 0.872340 (-7448 3775);
PAINT GREEN (-7448 3775);
DISPLAY INVISIBLE (-7448 3775);
FORCEADD TAP..1
R 2
(-7450 3825);
FORCEPROP 3 LASTPIN (-7400 3825) SIG_NAME M_A_CPU1_SA_CB<2>
J 0
(-7390 3835);
DISPLAY 0.659574 (-7390 3835);
PAINT MONO (-7390 3835);
DISPLAY INVISIBLE (-7390 3835);
FORCEPROP 1 LASTPIN (-7400 3825) BN 2
J 2
(-7388 3833);
DISPLAY 0.489362 (-7388 3833);
PAINT GREEN (-7388 3833);
FORCEPROP 2 LAST CDS_LIB mstr_standard
J 0
(-7450 3825);
DISPLAY 0.723404 (-7450 3825);
PAINT MONO (-7450 3825);
DISPLAY INVISIBLE (-7450 3825);
FORCEPROP 1 LAST BODY_TYPE PLUMBING
J 2
(-7450 3875);
DISPLAY 0.872340 (-7450 3875);
PAINT GREEN (-7450 3875);
DISPLAY INVISIBLE (-7450 3875);
FORCEPROP 1 LAST HDL_TAP TRUE
J 2
(-7775 3700);
DISPLAY 0.872340 (-7775 3700);
DISPLAY INVISIBLE (-7775 3700);
FORCEPROP 1 LAST PATH I33
J 2
(-7448 3825);
DISPLAY 0.872340 (-7448 3825);
PAINT GREEN (-7448 3825);
DISPLAY INVISIBLE (-7448 3825);
FORCEADD TAP..1
R 2
(-7450 3875);
FORCEPROP 3 LASTPIN (-7400 3875) SIG_NAME M_A_CPU1_SA_CB<3>
J 0
(-7390 3885);
DISPLAY 0.659574 (-7390 3885);
PAINT MONO (-7390 3885);
DISPLAY INVISIBLE (-7390 3885);
FORCEPROP 1 LASTPIN (-7400 3875) BN 3
J 2
(-7388 3883);
DISPLAY 0.489362 (-7388 3883);
PAINT GREEN (-7388 3883);
FORCEPROP 2 LAST CDS_LIB mstr_standard
J 0
(-7450 3875);
DISPLAY 0.723404 (-7450 3875);
PAINT MONO (-7450 3875);
DISPLAY INVISIBLE (-7450 3875);
FORCEPROP 1 LAST BODY_TYPE PLUMBING
J 2
(-7450 3925);
DISPLAY 0.872340 (-7450 3925);
PAINT GREEN (-7450 3925);
DISPLAY INVISIBLE (-7450 3925);
FORCEPROP 1 LAST HDL_TAP TRUE
J 2
(-7775 3750);
DISPLAY 0.872340 (-7775 3750);
DISPLAY INVISIBLE (-7775 3750);
FORCEPROP 1 LAST PATH I34
J 2
(-7448 3875);
DISPLAY 0.872340 (-7448 3875);
PAINT GREEN (-7448 3875);
DISPLAY INVISIBLE (-7448 3875);
FORCEADD TAP..1
R 2
(-7450 3925);
FORCEPROP 3 LASTPIN (-7400 3925) SIG_NAME M_A_CPU1_SA_CB<4>
J 0
(-7390 3935);
DISPLAY 0.659574 (-7390 3935);
PAINT MONO (-7390 3935);
DISPLAY INVISIBLE (-7390 3935);
FORCEPROP 1 LASTPIN (-7400 3925) BN 4
J 2
(-7388 3933);
DISPLAY 0.489362 (-7388 3933);
PAINT GREEN (-7388 3933);
FORCEPROP 2 LAST CDS_LIB mstr_standard
J 0
(-7450 3925);
DISPLAY 0.723404 (-7450 3925);
PAINT MONO (-7450 3925);
DISPLAY INVISIBLE (-7450 3925);
FORCEPROP 1 LAST BODY_TYPE PLUMBING
J 2
(-7450 3975);
DISPLAY 0.872340 (-7450 3975);
PAINT GREEN (-7450 3975);
DISPLAY INVISIBLE (-7450 3975);
FORCEPROP 1 LAST HDL_TAP TRUE
J 2
(-7775 3800);
DISPLAY 0.872340 (-7775 3800);
DISPLAY INVISIBLE (-7775 3800);
FORCEPROP 1 LAST PATH I35
J 2
(-7448 3925);
DISPLAY 0.872340 (-7448 3925);
PAINT GREEN (-7448 3925);
DISPLAY INVISIBLE (-7448 3925);
FORCEADD TAP..1
R 2
(-7450 3975);
FORCEPROP 3 LASTPIN (-7400 3975) SIG_NAME M_A_CPU1_SA_CB<5>
J 0
(-7390 3985);
DISPLAY 0.659574 (-7390 3985);
PAINT MONO (-7390 3985);
DISPLAY INVISIBLE (-7390 3985);
FORCEPROP 1 LASTPIN (-7400 3975) BN 5
J 2
(-7388 3983);
DISPLAY 0.489362 (-7388 3983);
PAINT GREEN (-7388 3983);
FORCEPROP 2 LAST CDS_LIB mstr_standard
J 0
(-7450 3975);
DISPLAY 0.723404 (-7450 3975);
PAINT MONO (-7450 3975);
DISPLAY INVISIBLE (-7450 3975);
FORCEPROP 1 LAST BODY_TYPE PLUMBING
J 2
(-7450 4025);
DISPLAY 0.872340 (-7450 4025);
PAINT GREEN (-7450 4025);
DISPLAY INVISIBLE (-7450 4025);
FORCEPROP 1 LAST HDL_TAP TRUE
J 2
(-7775 3850);
DISPLAY 0.872340 (-7775 3850);
DISPLAY INVISIBLE (-7775 3850);
FORCEPROP 1 LAST PATH I36
J 2
(-7448 3975);
DISPLAY 0.872340 (-7448 3975);
PAINT GREEN (-7448 3975);
DISPLAY INVISIBLE (-7448 3975);
FORCEADD TAP..1
R 2
(-7450 4025);
FORCEPROP 3 LASTPIN (-7400 4025) SIG_NAME M_A_CPU1_SA_CB<6>
J 0
(-7390 4035);
DISPLAY 0.659574 (-7390 4035);
PAINT MONO (-7390 4035);
DISPLAY INVISIBLE (-7390 4035);
FORCEPROP 1 LASTPIN (-7400 4025) BN 6
J 2
(-7388 4033);
DISPLAY 0.489362 (-7388 4033);
PAINT GREEN (-7388 4033);
FORCEPROP 2 LAST CDS_LIB mstr_standard
J 0
(-7450 4025);
DISPLAY 0.723404 (-7450 4025);
PAINT MONO (-7450 4025);
DISPLAY INVISIBLE (-7450 4025);
FORCEPROP 1 LAST BODY_TYPE PLUMBING
J 2
(-7450 4075);
DISPLAY 0.872340 (-7450 4075);
PAINT GREEN (-7450 4075);
DISPLAY INVISIBLE (-7450 4075);
FORCEPROP 1 LAST HDL_TAP TRUE
J 2
(-7775 3900);
DISPLAY 0.872340 (-7775 3900);
DISPLAY INVISIBLE (-7775 3900);
FORCEPROP 1 LAST PATH I37
J 2
(-7448 4025);
DISPLAY 0.872340 (-7448 4025);
PAINT GREEN (-7448 4025);
DISPLAY INVISIBLE (-7448 4025);
FORCEADD TAP..1
R 2
(-7450 4075);
FORCEPROP 3 LASTPIN (-7400 4075) SIG_NAME M_A_CPU1_SA_CB<7>
J 0
(-7390 4085);
DISPLAY 0.659574 (-7390 4085);
PAINT MONO (-7390 4085);
DISPLAY INVISIBLE (-7390 4085);
FORCEPROP 1 LASTPIN (-7400 4075) BN 7
J 2
(-7388 4083);
DISPLAY 0.489362 (-7388 4083);
PAINT GREEN (-7388 4083);
FORCEPROP 2 LAST CDS_LIB mstr_standard
J 0
(-7450 4075);
DISPLAY 0.723404 (-7450 4075);
PAINT MONO (-7450 4075);
DISPLAY INVISIBLE (-7450 4075);
FORCEPROP 1 LAST BODY_TYPE PLUMBING
J 2
(-7450 4125);
DISPLAY 0.872340 (-7450 4125);
PAINT GREEN (-7450 4125);
DISPLAY INVISIBLE (-7450 4125);
FORCEPROP 1 LAST HDL_TAP TRUE
J 2
(-7775 3950);
DISPLAY 0.872340 (-7775 3950);
DISPLAY INVISIBLE (-7775 3950);
FORCEPROP 1 LAST PATH I38
J 2
(-7448 4075);
DISPLAY 0.872340 (-7448 4075);
PAINT GREEN (-7448 4075);
DISPLAY INVISIBLE (-7448 4075);
FORCEADD TAP..1
(-5750 2325);
FORCEPROP 3 LASTPIN (-5800 2325) SIG_NAME M_A_CPU1_SB_DQ<1>
J 0
(-5790 2335);
DISPLAY 0.659574 (-5790 2335);
PAINT MONO (-5790 2335);
DISPLAY INVISIBLE (-5790 2335);
FORCEPROP 1 LASTPIN (-5800 2325) BN 1
J 0
(-5812 2333);
DISPLAY 0.489362 (-5812 2333);
PAINT GREEN (-5812 2333);
FORCEPROP 2 LAST CDS_LIB mstr_standard
J 0
(-5750 2325);
DISPLAY 0.723404 (-5750 2325);
PAINT MONO (-5750 2325);
DISPLAY INVISIBLE (-5750 2325);
FORCEPROP 1 LAST BODY_TYPE PLUMBING
J 0
(-5750 2375);
DISPLAY 0.872340 (-5750 2375);
PAINT GREEN (-5750 2375);
DISPLAY INVISIBLE (-5750 2375);
FORCEPROP 1 LAST HDL_TAP TRUE
J 0
(-5425 2200);
DISPLAY 0.872340 (-5425 2200);
DISPLAY INVISIBLE (-5425 2200);
FORCEPROP 1 LAST PATH I46
J 0
(-5752 2325);
DISPLAY 0.872340 (-5752 2325);
PAINT GREEN (-5752 2325);
DISPLAY INVISIBLE (-5752 2325);
FORCEADD TAP..1
(-5750 2275);
FORCEPROP 3 LASTPIN (-5800 2275) SIG_NAME M_A_CPU1_SB_DQ<0>
J 0
(-5790 2285);
DISPLAY 0.659574 (-5790 2285);
PAINT MONO (-5790 2285);
DISPLAY INVISIBLE (-5790 2285);
FORCEPROP 1 LASTPIN (-5800 2275) BN 0
J 0
(-5812 2283);
DISPLAY 0.489362 (-5812 2283);
PAINT GREEN (-5812 2283);
FORCEPROP 2 LAST CDS_LIB mstr_standard
J 0
(-5750 2275);
DISPLAY 0.723404 (-5750 2275);
PAINT MONO (-5750 2275);
DISPLAY INVISIBLE (-5750 2275);
FORCEPROP 1 LAST BODY_TYPE PLUMBING
J 0
(-5750 2325);
DISPLAY 0.872340 (-5750 2325);
PAINT GREEN (-5750 2325);
DISPLAY INVISIBLE (-5750 2325);
FORCEPROP 1 LAST HDL_TAP TRUE
J 0
(-5425 2150);
DISPLAY 0.872340 (-5425 2150);
DISPLAY INVISIBLE (-5425 2150);
FORCEPROP 1 LAST PATH I47
J 0
(-5752 2275);
DISPLAY 0.872340 (-5752 2275);
PAINT GREEN (-5752 2275);
DISPLAY INVISIBLE (-5752 2275);
FORCEADD TAP..1
(-5750 2475);
FORCEPROP 3 LASTPIN (-5800 2475) SIG_NAME M_A_CPU1_SB_DQ<4>
J 0
(-5790 2485);
DISPLAY 0.659574 (-5790 2485);
PAINT MONO (-5790 2485);
DISPLAY INVISIBLE (-5790 2485);
FORCEPROP 1 LASTPIN (-5800 2475) BN 4
J 0
(-5812 2483);
DISPLAY 0.489362 (-5812 2483);
PAINT GREEN (-5812 2483);
FORCEPROP 2 LAST CDS_LIB mstr_standard
J 0
(-5750 2475);
DISPLAY 0.723404 (-5750 2475);
PAINT MONO (-5750 2475);
DISPLAY INVISIBLE (-5750 2475);
FORCEPROP 1 LAST BODY_TYPE PLUMBING
J 0
(-5750 2525);
DISPLAY 0.872340 (-5750 2525);
PAINT GREEN (-5750 2525);
DISPLAY INVISIBLE (-5750 2525);
FORCEPROP 1 LAST HDL_TAP TRUE
J 0
(-5425 2350);
DISPLAY 0.872340 (-5425 2350);
DISPLAY INVISIBLE (-5425 2350);
FORCEPROP 1 LAST PATH I48
J 0
(-5752 2475);
DISPLAY 0.872340 (-5752 2475);
PAINT GREEN (-5752 2475);
DISPLAY INVISIBLE (-5752 2475);
FORCEADD TAP..1
(-5750 2425);
FORCEPROP 3 LASTPIN (-5800 2425) SIG_NAME M_A_CPU1_SB_DQ<3>
J 0
(-5790 2435);
DISPLAY 0.659574 (-5790 2435);
PAINT MONO (-5790 2435);
DISPLAY INVISIBLE (-5790 2435);
FORCEPROP 1 LASTPIN (-5800 2425) BN 3
J 0
(-5812 2433);
DISPLAY 0.489362 (-5812 2433);
PAINT GREEN (-5812 2433);
FORCEPROP 2 LAST CDS_LIB mstr_standard
J 0
(-5750 2425);
DISPLAY 0.723404 (-5750 2425);
PAINT MONO (-5750 2425);
DISPLAY INVISIBLE (-5750 2425);
FORCEPROP 1 LAST BODY_TYPE PLUMBING
J 0
(-5750 2475);
DISPLAY 0.872340 (-5750 2475);
PAINT GREEN (-5750 2475);
DISPLAY INVISIBLE (-5750 2475);
FORCEPROP 1 LAST HDL_TAP TRUE
J 0
(-5425 2300);
DISPLAY 0.872340 (-5425 2300);
DISPLAY INVISIBLE (-5425 2300);
FORCEPROP 1 LAST PATH I49
J 0
(-5752 2425);
DISPLAY 0.872340 (-5752 2425);
PAINT GREEN (-5752 2425);
DISPLAY INVISIBLE (-5752 2425);
FORCEADD TAP..1
(-5750 2375);
FORCEPROP 3 LASTPIN (-5800 2375) SIG_NAME M_A_CPU1_SB_DQ<2>
J 0
(-5790 2385);
DISPLAY 0.659574 (-5790 2385);
PAINT MONO (-5790 2385);
DISPLAY INVISIBLE (-5790 2385);
FORCEPROP 1 LASTPIN (-5800 2375) BN 2
J 0
(-5812 2383);
DISPLAY 0.489362 (-5812 2383);
PAINT GREEN (-5812 2383);
FORCEPROP 2 LAST CDS_LIB mstr_standard
J 0
(-5750 2375);
DISPLAY 0.723404 (-5750 2375);
PAINT MONO (-5750 2375);
DISPLAY INVISIBLE (-5750 2375);
FORCEPROP 1 LAST BODY_TYPE PLUMBING
J 0
(-5750 2425);
DISPLAY 0.872340 (-5750 2425);
PAINT GREEN (-5750 2425);
DISPLAY INVISIBLE (-5750 2425);
FORCEPROP 1 LAST HDL_TAP TRUE
J 0
(-5425 2250);
DISPLAY 0.872340 (-5425 2250);
DISPLAY INVISIBLE (-5425 2250);
FORCEPROP 1 LAST PATH I50
J 0
(-5752 2375);
DISPLAY 0.872340 (-5752 2375);
PAINT GREEN (-5752 2375);
DISPLAY INVISIBLE (-5752 2375);
FORCEADD TAP..1
(-5750 2525);
FORCEPROP 3 LASTPIN (-5800 2525) SIG_NAME M_A_CPU1_SB_DQ<5>
J 0
(-5790 2535);
DISPLAY 0.659574 (-5790 2535);
PAINT MONO (-5790 2535);
DISPLAY INVISIBLE (-5790 2535);
FORCEPROP 1 LASTPIN (-5800 2525) BN 5
J 0
(-5812 2533);
DISPLAY 0.489362 (-5812 2533);
PAINT GREEN (-5812 2533);
FORCEPROP 2 LAST CDS_LIB mstr_standard
J 0
(-5750 2525);
DISPLAY 0.723404 (-5750 2525);
PAINT MONO (-5750 2525);
DISPLAY INVISIBLE (-5750 2525);
FORCEPROP 1 LAST BODY_TYPE PLUMBING
J 0
(-5750 2575);
DISPLAY 0.872340 (-5750 2575);
PAINT GREEN (-5750 2575);
DISPLAY INVISIBLE (-5750 2575);
FORCEPROP 1 LAST HDL_TAP TRUE
J 0
(-5425 2400);
DISPLAY 0.872340 (-5425 2400);
DISPLAY INVISIBLE (-5425 2400);
FORCEPROP 1 LAST PATH I51
J 0
(-5752 2525);
DISPLAY 0.872340 (-5752 2525);
PAINT GREEN (-5752 2525);
DISPLAY INVISIBLE (-5752 2525);
FORCEADD TAP..1
(-5750 2575);
FORCEPROP 3 LASTPIN (-5800 2575) SIG_NAME M_A_CPU1_SB_DQ<6>
J 0
(-5790 2585);
DISPLAY 0.659574 (-5790 2585);
PAINT MONO (-5790 2585);
DISPLAY INVISIBLE (-5790 2585);
FORCEPROP 1 LASTPIN (-5800 2575) BN 6
J 0
(-5812 2583);
DISPLAY 0.489362 (-5812 2583);
PAINT GREEN (-5812 2583);
FORCEPROP 2 LAST CDS_LIB mstr_standard
J 0
(-5750 2575);
DISPLAY 0.723404 (-5750 2575);
PAINT MONO (-5750 2575);
DISPLAY INVISIBLE (-5750 2575);
FORCEPROP 1 LAST BODY_TYPE PLUMBING
J 0
(-5750 2625);
DISPLAY 0.872340 (-5750 2625);
PAINT GREEN (-5750 2625);
DISPLAY INVISIBLE (-5750 2625);
FORCEPROP 1 LAST HDL_TAP TRUE
J 0
(-5425 2450);
DISPLAY 0.872340 (-5425 2450);
DISPLAY INVISIBLE (-5425 2450);
FORCEPROP 1 LAST PATH I52
J 0
(-5752 2575);
DISPLAY 0.872340 (-5752 2575);
PAINT GREEN (-5752 2575);
DISPLAY INVISIBLE (-5752 2575);
FORCEADD TAP..1
(-5750 2725);
FORCEPROP 3 LASTPIN (-5800 2725) SIG_NAME M_A_CPU1_SB_DQ<9>
J 0
(-5790 2735);
DISPLAY 0.659574 (-5790 2735);
PAINT MONO (-5790 2735);
DISPLAY INVISIBLE (-5790 2735);
FORCEPROP 1 LASTPIN (-5800 2725) BN 9
J 0
(-5812 2733);
DISPLAY 0.489362 (-5812 2733);
PAINT GREEN (-5812 2733);
FORCEPROP 2 LAST CDS_LIB mstr_standard
J 0
(-5750 2725);
DISPLAY 0.723404 (-5750 2725);
PAINT MONO (-5750 2725);
DISPLAY INVISIBLE (-5750 2725);
FORCEPROP 1 LAST BODY_TYPE PLUMBING
J 0
(-5750 2775);
DISPLAY 0.872340 (-5750 2775);
PAINT GREEN (-5750 2775);
DISPLAY INVISIBLE (-5750 2775);
FORCEPROP 1 LAST HDL_TAP TRUE
J 0
(-5425 2600);
DISPLAY 0.872340 (-5425 2600);
DISPLAY INVISIBLE (-5425 2600);
FORCEPROP 1 LAST PATH I53
J 0
(-5752 2725);
DISPLAY 0.872340 (-5752 2725);
PAINT GREEN (-5752 2725);
DISPLAY INVISIBLE (-5752 2725);
FORCEADD TAP..1
(-5750 2675);
FORCEPROP 3 LASTPIN (-5800 2675) SIG_NAME M_A_CPU1_SB_DQ<8>
J 0
(-5790 2685);
DISPLAY 0.659574 (-5790 2685);
PAINT MONO (-5790 2685);
DISPLAY INVISIBLE (-5790 2685);
FORCEPROP 1 LASTPIN (-5800 2675) BN 8
J 0
(-5812 2683);
DISPLAY 0.489362 (-5812 2683);
PAINT GREEN (-5812 2683);
FORCEPROP 2 LAST CDS_LIB mstr_standard
J 0
(-5750 2675);
DISPLAY 0.723404 (-5750 2675);
PAINT MONO (-5750 2675);
DISPLAY INVISIBLE (-5750 2675);
FORCEPROP 1 LAST BODY_TYPE PLUMBING
J 0
(-5750 2725);
DISPLAY 0.872340 (-5750 2725);
PAINT GREEN (-5750 2725);
DISPLAY INVISIBLE (-5750 2725);
FORCEPROP 1 LAST HDL_TAP TRUE
J 0
(-5425 2550);
DISPLAY 0.872340 (-5425 2550);
DISPLAY INVISIBLE (-5425 2550);
FORCEPROP 1 LAST PATH I54
J 0
(-5752 2675);
DISPLAY 0.872340 (-5752 2675);
PAINT GREEN (-5752 2675);
DISPLAY INVISIBLE (-5752 2675);
FORCEADD TAP..1
(-5750 2625);
FORCEPROP 3 LASTPIN (-5800 2625) SIG_NAME M_A_CPU1_SB_DQ<7>
J 0
(-5790 2635);
DISPLAY 0.659574 (-5790 2635);
PAINT MONO (-5790 2635);
DISPLAY INVISIBLE (-5790 2635);
FORCEPROP 1 LASTPIN (-5800 2625) BN 7
J 0
(-5812 2633);
DISPLAY 0.489362 (-5812 2633);
PAINT GREEN (-5812 2633);
FORCEPROP 2 LAST CDS_LIB mstr_standard
J 0
(-5750 2625);
DISPLAY 0.723404 (-5750 2625);
PAINT MONO (-5750 2625);
DISPLAY INVISIBLE (-5750 2625);
FORCEPROP 1 LAST BODY_TYPE PLUMBING
J 0
(-5750 2675);
DISPLAY 0.872340 (-5750 2675);
PAINT GREEN (-5750 2675);
DISPLAY INVISIBLE (-5750 2675);
FORCEPROP 1 LAST HDL_TAP TRUE
J 0
(-5425 2500);
DISPLAY 0.872340 (-5425 2500);
DISPLAY INVISIBLE (-5425 2500);
FORCEPROP 1 LAST PATH I55
J 0
(-5752 2625);
DISPLAY 0.872340 (-5752 2625);
PAINT GREEN (-5752 2625);
DISPLAY INVISIBLE (-5752 2625);
FORCEADD TAP..1
(-5750 2775);
FORCEPROP 3 LASTPIN (-5800 2775) SIG_NAME M_A_CPU1_SB_DQ<10>
J 0
(-5790 2785);
DISPLAY 0.659574 (-5790 2785);
PAINT MONO (-5790 2785);
DISPLAY INVISIBLE (-5790 2785);
FORCEPROP 1 LASTPIN (-5800 2775) BN 10
J 0
(-5812 2783);
DISPLAY 0.489362 (-5812 2783);
PAINT GREEN (-5812 2783);
FORCEPROP 2 LAST CDS_LIB mstr_standard
J 0
(-5750 2775);
DISPLAY 0.723404 (-5750 2775);
PAINT MONO (-5750 2775);
DISPLAY INVISIBLE (-5750 2775);
FORCEPROP 1 LAST BODY_TYPE PLUMBING
J 0
(-5750 2825);
DISPLAY 0.872340 (-5750 2825);
PAINT GREEN (-5750 2825);
DISPLAY INVISIBLE (-5750 2825);
FORCEPROP 1 LAST HDL_TAP TRUE
J 0
(-5425 2650);
DISPLAY 0.872340 (-5425 2650);
DISPLAY INVISIBLE (-5425 2650);
FORCEPROP 1 LAST PATH I56
J 0
(-5752 2775);
DISPLAY 0.872340 (-5752 2775);
PAINT GREEN (-5752 2775);
DISPLAY INVISIBLE (-5752 2775);
FORCEADD TAP..1
(-5750 2825);
FORCEPROP 3 LASTPIN (-5800 2825) SIG_NAME M_A_CPU1_SB_DQ<11>
J 0
(-5790 2835);
DISPLAY 0.659574 (-5790 2835);
PAINT MONO (-5790 2835);
DISPLAY INVISIBLE (-5790 2835);
FORCEPROP 1 LASTPIN (-5800 2825) BN 11
J 0
(-5812 2833);
DISPLAY 0.489362 (-5812 2833);
PAINT GREEN (-5812 2833);
FORCEPROP 2 LAST CDS_LIB mstr_standard
J 0
(-5750 2825);
DISPLAY 0.723404 (-5750 2825);
PAINT MONO (-5750 2825);
DISPLAY INVISIBLE (-5750 2825);
FORCEPROP 1 LAST BODY_TYPE PLUMBING
J 0
(-5750 2875);
DISPLAY 0.872340 (-5750 2875);
PAINT GREEN (-5750 2875);
DISPLAY INVISIBLE (-5750 2875);
FORCEPROP 1 LAST HDL_TAP TRUE
J 0
(-5425 2700);
DISPLAY 0.872340 (-5425 2700);
DISPLAY INVISIBLE (-5425 2700);
FORCEPROP 1 LAST PATH I57
J 0
(-5752 2825);
DISPLAY 0.872340 (-5752 2825);
PAINT GREEN (-5752 2825);
DISPLAY INVISIBLE (-5752 2825);
FORCEADD TAP..1
(-5750 2975);
FORCEPROP 3 LASTPIN (-5800 2975) SIG_NAME M_A_CPU1_SB_DQ<14>
J 0
(-5790 2985);
DISPLAY 0.659574 (-5790 2985);
PAINT MONO (-5790 2985);
DISPLAY INVISIBLE (-5790 2985);
FORCEPROP 1 LASTPIN (-5800 2975) BN 14
J 0
(-5812 2983);
DISPLAY 0.489362 (-5812 2983);
PAINT GREEN (-5812 2983);
FORCEPROP 2 LAST CDS_LIB mstr_standard
J 0
(-5750 2975);
DISPLAY 0.723404 (-5750 2975);
PAINT MONO (-5750 2975);
DISPLAY INVISIBLE (-5750 2975);
FORCEPROP 1 LAST BODY_TYPE PLUMBING
J 0
(-5750 3025);
DISPLAY 0.872340 (-5750 3025);
PAINT GREEN (-5750 3025);
DISPLAY INVISIBLE (-5750 3025);
FORCEPROP 1 LAST HDL_TAP TRUE
J 0
(-5425 2850);
DISPLAY 0.872340 (-5425 2850);
DISPLAY INVISIBLE (-5425 2850);
FORCEPROP 1 LAST PATH I58
J 0
(-5752 2975);
DISPLAY 0.872340 (-5752 2975);
PAINT GREEN (-5752 2975);
DISPLAY INVISIBLE (-5752 2975);
FORCEADD TAP..1
(-5750 2925);
FORCEPROP 3 LASTPIN (-5800 2925) SIG_NAME M_A_CPU1_SB_DQ<13>
J 0
(-5790 2935);
DISPLAY 0.659574 (-5790 2935);
PAINT MONO (-5790 2935);
DISPLAY INVISIBLE (-5790 2935);
FORCEPROP 1 LASTPIN (-5800 2925) BN 13
J 0
(-5812 2933);
DISPLAY 0.489362 (-5812 2933);
PAINT GREEN (-5812 2933);
FORCEPROP 2 LAST CDS_LIB mstr_standard
J 0
(-5750 2925);
DISPLAY 0.723404 (-5750 2925);
PAINT MONO (-5750 2925);
DISPLAY INVISIBLE (-5750 2925);
FORCEPROP 1 LAST BODY_TYPE PLUMBING
J 0
(-5750 2975);
DISPLAY 0.872340 (-5750 2975);
PAINT GREEN (-5750 2975);
DISPLAY INVISIBLE (-5750 2975);
FORCEPROP 1 LAST HDL_TAP TRUE
J 0
(-5425 2800);
DISPLAY 0.872340 (-5425 2800);
DISPLAY INVISIBLE (-5425 2800);
FORCEPROP 1 LAST PATH I59
J 0
(-5752 2925);
DISPLAY 0.872340 (-5752 2925);
PAINT GREEN (-5752 2925);
DISPLAY INVISIBLE (-5752 2925);
FORCEADD OFFPAGE..1
(-8050 2975);
FORCEPROP 2 LAST $XR0 97 
J 0
(-8271 2975);
DISPLAY 0.638298 (-8271 2975);
PAINT MONO (-8271 2975);
FORCEPROP 2 LAST CDS_LIB mstr_standard
J 0
(-8050 2975);
DISPLAY 0.808511 (-8050 2975);
DISPLAY INVISIBLE (-8050 2975);
FORCEPROP 1 LAST OFFPAGE TRUE
J 0
(-7725 2850);
DISPLAY 0.872340 (-7725 2850);
PAINT GREEN (-7725 2850);
DISPLAY INVISIBLE (-7725 2850);
FORCEPROP 1 LAST COMMENT_BODY TRUE
J 0
(-7925 2875);
DISPLAY 0.872340 (-7925 2875);
PAINT GREEN (-7925 2875);
DISPLAY INVISIBLE (-7925 2875);
FORCEPROP 2 LAST PATH I6
J 0
(-8300 3025);
DISPLAY 1.021277 (-8300 3025);
DISPLAY INVISIBLE (-8300 3025);
FORCEADD TAP..1
(-5750 2875);
FORCEPROP 3 LASTPIN (-5800 2875) SIG_NAME M_A_CPU1_SB_DQ<12>
J 0
(-5790 2885);
DISPLAY 0.659574 (-5790 2885);
PAINT MONO (-5790 2885);
DISPLAY INVISIBLE (-5790 2885);
FORCEPROP 1 LASTPIN (-5800 2875) BN 12
J 0
(-5812 2883);
DISPLAY 0.489362 (-5812 2883);
PAINT GREEN (-5812 2883);
FORCEPROP 2 LAST CDS_LIB mstr_standard
J 0
(-5750 2875);
DISPLAY 0.723404 (-5750 2875);
PAINT MONO (-5750 2875);
DISPLAY INVISIBLE (-5750 2875);
FORCEPROP 1 LAST BODY_TYPE PLUMBING
J 0
(-5750 2925);
DISPLAY 0.872340 (-5750 2925);
PAINT GREEN (-5750 2925);
DISPLAY INVISIBLE (-5750 2925);
FORCEPROP 1 LAST HDL_TAP TRUE
J 0
(-5425 2750);
DISPLAY 0.872340 (-5425 2750);
DISPLAY INVISIBLE (-5425 2750);
FORCEPROP 1 LAST PATH I60
J 0
(-5752 2875);
DISPLAY 0.872340 (-5752 2875);
PAINT GREEN (-5752 2875);
DISPLAY INVISIBLE (-5752 2875);
FORCEADD TAP..1
(-5750 3075);
FORCEPROP 3 LASTPIN (-5800 3075) SIG_NAME M_A_CPU1_SB_DQ<16>
J 0
(-5790 3085);
DISPLAY 0.659574 (-5790 3085);
PAINT MONO (-5790 3085);
DISPLAY INVISIBLE (-5790 3085);
FORCEPROP 1 LASTPIN (-5800 3075) BN 16
J 0
(-5812 3083);
DISPLAY 0.489362 (-5812 3083);
PAINT GREEN (-5812 3083);
FORCEPROP 2 LAST CDS_LIB mstr_standard
J 0
(-5750 3075);
DISPLAY 0.723404 (-5750 3075);
PAINT MONO (-5750 3075);
DISPLAY INVISIBLE (-5750 3075);
FORCEPROP 1 LAST BODY_TYPE PLUMBING
J 0
(-5750 3125);
DISPLAY 0.872340 (-5750 3125);
PAINT GREEN (-5750 3125);
DISPLAY INVISIBLE (-5750 3125);
FORCEPROP 1 LAST HDL_TAP TRUE
J 0
(-5425 2950);
DISPLAY 0.872340 (-5425 2950);
DISPLAY INVISIBLE (-5425 2950);
FORCEPROP 1 LAST PATH I61
J 0
(-5752 3075);
DISPLAY 0.872340 (-5752 3075);
PAINT GREEN (-5752 3075);
DISPLAY INVISIBLE (-5752 3075);
FORCEADD TAP..1
(-5750 3025);
FORCEPROP 3 LASTPIN (-5800 3025) SIG_NAME M_A_CPU1_SB_DQ<15>
J 0
(-5790 3035);
DISPLAY 0.659574 (-5790 3035);
PAINT MONO (-5790 3035);
DISPLAY INVISIBLE (-5790 3035);
FORCEPROP 1 LASTPIN (-5800 3025) BN 15
J 0
(-5812 3033);
DISPLAY 0.489362 (-5812 3033);
PAINT GREEN (-5812 3033);
FORCEPROP 2 LAST CDS_LIB mstr_standard
J 0
(-5750 3025);
DISPLAY 0.723404 (-5750 3025);
PAINT MONO (-5750 3025);
DISPLAY INVISIBLE (-5750 3025);
FORCEPROP 1 LAST BODY_TYPE PLUMBING
J 0
(-5750 3075);
DISPLAY 0.872340 (-5750 3075);
PAINT GREEN (-5750 3075);
DISPLAY INVISIBLE (-5750 3075);
FORCEPROP 1 LAST HDL_TAP TRUE
J 0
(-5425 2900);
DISPLAY 0.872340 (-5425 2900);
DISPLAY INVISIBLE (-5425 2900);
FORCEPROP 1 LAST PATH I62
J 0
(-5752 3025);
DISPLAY 0.872340 (-5752 3025);
PAINT GREEN (-5752 3025);
DISPLAY INVISIBLE (-5752 3025);
FORCEADD TAP..1
(-5750 3125);
FORCEPROP 3 LASTPIN (-5800 3125) SIG_NAME M_A_CPU1_SB_DQ<17>
J 0
(-5790 3135);
DISPLAY 0.659574 (-5790 3135);
PAINT MONO (-5790 3135);
DISPLAY INVISIBLE (-5790 3135);
FORCEPROP 1 LASTPIN (-5800 3125) BN 17
J 0
(-5812 3133);
DISPLAY 0.489362 (-5812 3133);
PAINT GREEN (-5812 3133);
FORCEPROP 2 LAST CDS_LIB mstr_standard
J 0
(-5750 3125);
DISPLAY 0.723404 (-5750 3125);
PAINT MONO (-5750 3125);
DISPLAY INVISIBLE (-5750 3125);
FORCEPROP 1 LAST BODY_TYPE PLUMBING
J 0
(-5750 3175);
DISPLAY 0.872340 (-5750 3175);
PAINT GREEN (-5750 3175);
DISPLAY INVISIBLE (-5750 3175);
FORCEPROP 1 LAST HDL_TAP TRUE
J 0
(-5425 3000);
DISPLAY 0.872340 (-5425 3000);
DISPLAY INVISIBLE (-5425 3000);
FORCEPROP 1 LAST PATH I63
J 0
(-5752 3125);
DISPLAY 0.872340 (-5752 3125);
PAINT GREEN (-5752 3125);
DISPLAY INVISIBLE (-5752 3125);
FORCEADD TAP..1
(-5750 3225);
FORCEPROP 3 LASTPIN (-5800 3225) SIG_NAME M_A_CPU1_SB_DQ<19>
J 0
(-5790 3235);
DISPLAY 0.659574 (-5790 3235);
PAINT MONO (-5790 3235);
DISPLAY INVISIBLE (-5790 3235);
FORCEPROP 1 LASTPIN (-5800 3225) BN 19
J 0
(-5812 3233);
DISPLAY 0.489362 (-5812 3233);
PAINT GREEN (-5812 3233);
FORCEPROP 2 LAST CDS_LIB mstr_standard
J 0
(-5750 3225);
DISPLAY 0.723404 (-5750 3225);
PAINT MONO (-5750 3225);
DISPLAY INVISIBLE (-5750 3225);
FORCEPROP 1 LAST BODY_TYPE PLUMBING
J 0
(-5750 3275);
DISPLAY 0.872340 (-5750 3275);
PAINT GREEN (-5750 3275);
DISPLAY INVISIBLE (-5750 3275);
FORCEPROP 1 LAST HDL_TAP TRUE
J 0
(-5425 3100);
DISPLAY 0.872340 (-5425 3100);
DISPLAY INVISIBLE (-5425 3100);
FORCEPROP 1 LAST PATH I64
J 0
(-5752 3225);
DISPLAY 0.872340 (-5752 3225);
PAINT GREEN (-5752 3225);
DISPLAY INVISIBLE (-5752 3225);
FORCEADD TAP..1
(-5750 3175);
FORCEPROP 3 LASTPIN (-5800 3175) SIG_NAME M_A_CPU1_SB_DQ<18>
J 0
(-5790 3185);
DISPLAY 0.659574 (-5790 3185);
PAINT MONO (-5790 3185);
DISPLAY INVISIBLE (-5790 3185);
FORCEPROP 1 LASTPIN (-5800 3175) BN 18
J 0
(-5812 3183);
DISPLAY 0.489362 (-5812 3183);
PAINT GREEN (-5812 3183);
FORCEPROP 2 LAST CDS_LIB mstr_standard
J 0
(-5750 3175);
DISPLAY 0.723404 (-5750 3175);
PAINT MONO (-5750 3175);
DISPLAY INVISIBLE (-5750 3175);
FORCEPROP 1 LAST BODY_TYPE PLUMBING
J 0
(-5750 3225);
DISPLAY 0.872340 (-5750 3225);
PAINT GREEN (-5750 3225);
DISPLAY INVISIBLE (-5750 3225);
FORCEPROP 1 LAST HDL_TAP TRUE
J 0
(-5425 3050);
DISPLAY 0.872340 (-5425 3050);
DISPLAY INVISIBLE (-5425 3050);
FORCEPROP 1 LAST PATH I65
J 0
(-5752 3175);
DISPLAY 0.872340 (-5752 3175);
PAINT GREEN (-5752 3175);
DISPLAY INVISIBLE (-5752 3175);
FORCEADD TAP..1
(-5750 3275);
FORCEPROP 3 LASTPIN (-5800 3275) SIG_NAME M_A_CPU1_SB_DQ<20>
J 0
(-5790 3285);
DISPLAY 0.659574 (-5790 3285);
PAINT MONO (-5790 3285);
DISPLAY INVISIBLE (-5790 3285);
FORCEPROP 1 LASTPIN (-5800 3275) BN 20
J 0
(-5812 3283);
DISPLAY 0.489362 (-5812 3283);
PAINT GREEN (-5812 3283);
FORCEPROP 2 LAST CDS_LIB mstr_standard
J 0
(-5750 3275);
DISPLAY 0.723404 (-5750 3275);
PAINT MONO (-5750 3275);
DISPLAY INVISIBLE (-5750 3275);
FORCEPROP 1 LAST BODY_TYPE PLUMBING
J 0
(-5750 3325);
DISPLAY 0.872340 (-5750 3325);
PAINT GREEN (-5750 3325);
DISPLAY INVISIBLE (-5750 3325);
FORCEPROP 1 LAST HDL_TAP TRUE
J 0
(-5425 3150);
DISPLAY 0.872340 (-5425 3150);
DISPLAY INVISIBLE (-5425 3150);
FORCEPROP 1 LAST PATH I66
J 0
(-5752 3275);
DISPLAY 0.872340 (-5752 3275);
PAINT GREEN (-5752 3275);
DISPLAY INVISIBLE (-5752 3275);
FORCEADD TAP..1
(-5750 3325);
FORCEPROP 3 LASTPIN (-5800 3325) SIG_NAME M_A_CPU1_SB_DQ<21>
J 0
(-5790 3335);
DISPLAY 0.659574 (-5790 3335);
PAINT MONO (-5790 3335);
DISPLAY INVISIBLE (-5790 3335);
FORCEPROP 1 LASTPIN (-5800 3325) BN 21
J 0
(-5812 3333);
DISPLAY 0.489362 (-5812 3333);
PAINT GREEN (-5812 3333);
FORCEPROP 2 LAST CDS_LIB mstr_standard
J 0
(-5750 3325);
DISPLAY 0.723404 (-5750 3325);
PAINT MONO (-5750 3325);
DISPLAY INVISIBLE (-5750 3325);
FORCEPROP 1 LAST BODY_TYPE PLUMBING
J 0
(-5750 3375);
DISPLAY 0.872340 (-5750 3375);
PAINT GREEN (-5750 3375);
DISPLAY INVISIBLE (-5750 3375);
FORCEPROP 1 LAST HDL_TAP TRUE
J 0
(-5425 3200);
DISPLAY 0.872340 (-5425 3200);
DISPLAY INVISIBLE (-5425 3200);
FORCEPROP 1 LAST PATH I67
J 0
(-5752 3325);
DISPLAY 0.872340 (-5752 3325);
PAINT GREEN (-5752 3325);
DISPLAY INVISIBLE (-5752 3325);
FORCEADD TAP..1
(-5750 3375);
FORCEPROP 3 LASTPIN (-5800 3375) SIG_NAME M_A_CPU1_SB_DQ<22>
J 0
(-5790 3385);
DISPLAY 0.659574 (-5790 3385);
PAINT MONO (-5790 3385);
DISPLAY INVISIBLE (-5790 3385);
FORCEPROP 1 LASTPIN (-5800 3375) BN 22
J 0
(-5812 3383);
DISPLAY 0.489362 (-5812 3383);
PAINT GREEN (-5812 3383);
FORCEPROP 2 LAST CDS_LIB mstr_standard
J 0
(-5750 3375);
DISPLAY 0.723404 (-5750 3375);
PAINT MONO (-5750 3375);
DISPLAY INVISIBLE (-5750 3375);
FORCEPROP 1 LAST BODY_TYPE PLUMBING
J 0
(-5750 3425);
DISPLAY 0.872340 (-5750 3425);
PAINT GREEN (-5750 3425);
DISPLAY INVISIBLE (-5750 3425);
FORCEPROP 1 LAST HDL_TAP TRUE
J 0
(-5425 3250);
DISPLAY 0.872340 (-5425 3250);
DISPLAY INVISIBLE (-5425 3250);
FORCEPROP 1 LAST PATH I68
J 0
(-5752 3375);
DISPLAY 0.872340 (-5752 3375);
PAINT GREEN (-5752 3375);
DISPLAY INVISIBLE (-5752 3375);
FORCEADD TAP..1
(-5750 3475);
FORCEPROP 3 LASTPIN (-5800 3475) SIG_NAME M_A_CPU1_SB_DQ<24>
J 0
(-5790 3485);
DISPLAY 0.659574 (-5790 3485);
PAINT MONO (-5790 3485);
DISPLAY INVISIBLE (-5790 3485);
FORCEPROP 1 LASTPIN (-5800 3475) BN 24
J 0
(-5812 3483);
DISPLAY 0.489362 (-5812 3483);
PAINT GREEN (-5812 3483);
FORCEPROP 2 LAST CDS_LIB mstr_standard
J 0
(-5750 3475);
DISPLAY 0.723404 (-5750 3475);
PAINT MONO (-5750 3475);
DISPLAY INVISIBLE (-5750 3475);
FORCEPROP 1 LAST BODY_TYPE PLUMBING
J 0
(-5750 3525);
DISPLAY 0.872340 (-5750 3525);
PAINT GREEN (-5750 3525);
DISPLAY INVISIBLE (-5750 3525);
FORCEPROP 1 LAST HDL_TAP TRUE
J 0
(-5425 3350);
DISPLAY 0.872340 (-5425 3350);
DISPLAY INVISIBLE (-5425 3350);
FORCEPROP 1 LAST PATH I69
J 0
(-5752 3475);
DISPLAY 0.872340 (-5752 3475);
PAINT GREEN (-5752 3475);
DISPLAY INVISIBLE (-5752 3475);
FORCEADD OFFPAGE..5
(-8050 3125);
FORCEPROP 2 LAST $XR0 37 
J 0
(-8304 3125);
DISPLAY 0.638298 (-8304 3125);
PAINT MONO (-8304 3125);
FORCEPROP 2 LAST CDS_LIB mstr_standard
J 0
(-8050 3125);
DISPLAY INVISIBLE (-8050 3125);
FORCEPROP 1 LAST OFFPAGE TRUE
J 0
(-7725 3000);
DISPLAY 0.872340 (-7725 3000);
PAINT GREEN (-7725 3000);
DISPLAY INVISIBLE (-7725 3000);
FORCEPROP 1 LAST COMMENT_BODY TRUE
J 0
(-7950 3050);
DISPLAY 0.872340 (-7950 3050);
PAINT GREEN (-7950 3050);
DISPLAY INVISIBLE (-7950 3050);
FORCEPROP 2 LAST PATH I7
J 0
(-8300 3175);
DISPLAY 1.021277 (-8300 3175);
DISPLAY INVISIBLE (-8300 3175);
FORCEADD TAP..1
(-5750 3425);
FORCEPROP 3 LASTPIN (-5800 3425) SIG_NAME M_A_CPU1_SB_DQ<23>
J 0
(-5790 3435);
DISPLAY 0.659574 (-5790 3435);
PAINT MONO (-5790 3435);
DISPLAY INVISIBLE (-5790 3435);
FORCEPROP 1 LASTPIN (-5800 3425) BN 23
J 0
(-5812 3433);
DISPLAY 0.489362 (-5812 3433);
PAINT GREEN (-5812 3433);
FORCEPROP 2 LAST CDS_LIB mstr_standard
J 0
(-5750 3425);
DISPLAY 0.723404 (-5750 3425);
PAINT MONO (-5750 3425);
DISPLAY INVISIBLE (-5750 3425);
FORCEPROP 1 LAST BODY_TYPE PLUMBING
J 0
(-5750 3475);
DISPLAY 0.872340 (-5750 3475);
PAINT GREEN (-5750 3475);
DISPLAY INVISIBLE (-5750 3475);
FORCEPROP 1 LAST HDL_TAP TRUE
J 0
(-5425 3300);
DISPLAY 0.872340 (-5425 3300);
DISPLAY INVISIBLE (-5425 3300);
FORCEPROP 1 LAST PATH I70
J 0
(-5752 3425);
DISPLAY 0.872340 (-5752 3425);
PAINT GREEN (-5752 3425);
DISPLAY INVISIBLE (-5752 3425);
FORCEADD TAP..1
(-5750 3525);
FORCEPROP 3 LASTPIN (-5800 3525) SIG_NAME M_A_CPU1_SB_DQ<25>
J 0
(-5790 3535);
DISPLAY 0.659574 (-5790 3535);
PAINT MONO (-5790 3535);
DISPLAY INVISIBLE (-5790 3535);
FORCEPROP 1 LASTPIN (-5800 3525) BN 25
J 0
(-5812 3533);
DISPLAY 0.489362 (-5812 3533);
PAINT GREEN (-5812 3533);
FORCEPROP 2 LAST CDS_LIB mstr_standard
J 0
(-5750 3525);
DISPLAY 0.723404 (-5750 3525);
PAINT MONO (-5750 3525);
DISPLAY INVISIBLE (-5750 3525);
FORCEPROP 1 LAST BODY_TYPE PLUMBING
J 0
(-5750 3575);
DISPLAY 0.872340 (-5750 3575);
PAINT GREEN (-5750 3575);
DISPLAY INVISIBLE (-5750 3575);
FORCEPROP 1 LAST HDL_TAP TRUE
J 0
(-5425 3400);
DISPLAY 0.872340 (-5425 3400);
DISPLAY INVISIBLE (-5425 3400);
FORCEPROP 1 LAST PATH I71
J 0
(-5752 3525);
DISPLAY 0.872340 (-5752 3525);
PAINT GREEN (-5752 3525);
DISPLAY INVISIBLE (-5752 3525);
FORCEADD TAP..1
(-5750 3575);
FORCEPROP 3 LASTPIN (-5800 3575) SIG_NAME M_A_CPU1_SB_DQ<26>
J 0
(-5790 3585);
DISPLAY 0.659574 (-5790 3585);
PAINT MONO (-5790 3585);
DISPLAY INVISIBLE (-5790 3585);
FORCEPROP 1 LASTPIN (-5800 3575) BN 26
J 0
(-5812 3583);
DISPLAY 0.489362 (-5812 3583);
PAINT GREEN (-5812 3583);
FORCEPROP 2 LAST CDS_LIB mstr_standard
J 0
(-5750 3575);
DISPLAY 0.723404 (-5750 3575);
PAINT MONO (-5750 3575);
DISPLAY INVISIBLE (-5750 3575);
FORCEPROP 1 LAST BODY_TYPE PLUMBING
J 0
(-5750 3625);
DISPLAY 0.872340 (-5750 3625);
PAINT GREEN (-5750 3625);
DISPLAY INVISIBLE (-5750 3625);
FORCEPROP 1 LAST HDL_TAP TRUE
J 0
(-5425 3450);
DISPLAY 0.872340 (-5425 3450);
DISPLAY INVISIBLE (-5425 3450);
FORCEPROP 1 LAST PATH I72
J 0
(-5752 3575);
DISPLAY 0.872340 (-5752 3575);
PAINT GREEN (-5752 3575);
DISPLAY INVISIBLE (-5752 3575);
FORCEADD TAP..1
(-5750 3625);
FORCEPROP 3 LASTPIN (-5800 3625) SIG_NAME M_A_CPU1_SB_DQ<27>
J 0
(-5790 3635);
DISPLAY 0.659574 (-5790 3635);
PAINT MONO (-5790 3635);
DISPLAY INVISIBLE (-5790 3635);
FORCEPROP 1 LASTPIN (-5800 3625) BN 27
J 0
(-5812 3633);
DISPLAY 0.489362 (-5812 3633);
PAINT GREEN (-5812 3633);
FORCEPROP 2 LAST CDS_LIB mstr_standard
J 0
(-5750 3625);
DISPLAY 0.723404 (-5750 3625);
PAINT MONO (-5750 3625);
DISPLAY INVISIBLE (-5750 3625);
FORCEPROP 1 LAST BODY_TYPE PLUMBING
J 0
(-5750 3675);
DISPLAY 0.872340 (-5750 3675);
PAINT GREEN (-5750 3675);
DISPLAY INVISIBLE (-5750 3675);
FORCEPROP 1 LAST HDL_TAP TRUE
J 0
(-5425 3500);
DISPLAY 0.872340 (-5425 3500);
DISPLAY INVISIBLE (-5425 3500);
FORCEPROP 1 LAST PATH I73
J 0
(-5752 3625);
DISPLAY 0.872340 (-5752 3625);
PAINT GREEN (-5752 3625);
DISPLAY INVISIBLE (-5752 3625);
FORCEADD TAP..1
(-5750 3725);
FORCEPROP 3 LASTPIN (-5800 3725) SIG_NAME M_A_CPU1_SB_DQ<29>
J 0
(-5790 3735);
DISPLAY 0.659574 (-5790 3735);
PAINT MONO (-5790 3735);
DISPLAY INVISIBLE (-5790 3735);
FORCEPROP 1 LASTPIN (-5800 3725) BN 29
J 0
(-5812 3733);
DISPLAY 0.489362 (-5812 3733);
PAINT GREEN (-5812 3733);
FORCEPROP 2 LAST CDS_LIB mstr_standard
J 0
(-5750 3725);
DISPLAY 0.723404 (-5750 3725);
PAINT MONO (-5750 3725);
DISPLAY INVISIBLE (-5750 3725);
FORCEPROP 1 LAST BODY_TYPE PLUMBING
J 0
(-5750 3775);
DISPLAY 0.872340 (-5750 3775);
PAINT GREEN (-5750 3775);
DISPLAY INVISIBLE (-5750 3775);
FORCEPROP 1 LAST HDL_TAP TRUE
J 0
(-5425 3600);
DISPLAY 0.872340 (-5425 3600);
DISPLAY INVISIBLE (-5425 3600);
FORCEPROP 1 LAST PATH I74
J 0
(-5752 3725);
DISPLAY 0.872340 (-5752 3725);
PAINT GREEN (-5752 3725);
DISPLAY INVISIBLE (-5752 3725);
FORCEADD TAP..1
(-5750 3675);
FORCEPROP 3 LASTPIN (-5800 3675) SIG_NAME M_A_CPU1_SB_DQ<28>
J 0
(-5790 3685);
DISPLAY 0.659574 (-5790 3685);
PAINT MONO (-5790 3685);
DISPLAY INVISIBLE (-5790 3685);
FORCEPROP 1 LASTPIN (-5800 3675) BN 28
J 0
(-5812 3683);
DISPLAY 0.489362 (-5812 3683);
PAINT GREEN (-5812 3683);
FORCEPROP 2 LAST CDS_LIB mstr_standard
J 0
(-5750 3675);
DISPLAY 0.723404 (-5750 3675);
PAINT MONO (-5750 3675);
DISPLAY INVISIBLE (-5750 3675);
FORCEPROP 1 LAST BODY_TYPE PLUMBING
J 0
(-5750 3725);
DISPLAY 0.872340 (-5750 3725);
PAINT GREEN (-5750 3725);
DISPLAY INVISIBLE (-5750 3725);
FORCEPROP 1 LAST HDL_TAP TRUE
J 0
(-5425 3550);
DISPLAY 0.872340 (-5425 3550);
DISPLAY INVISIBLE (-5425 3550);
FORCEPROP 1 LAST PATH I75
J 0
(-5752 3675);
DISPLAY 0.872340 (-5752 3675);
PAINT GREEN (-5752 3675);
DISPLAY INVISIBLE (-5752 3675);
FORCEADD TAP..1
(-5750 3775);
FORCEPROP 3 LASTPIN (-5800 3775) SIG_NAME M_A_CPU1_SB_DQ<30>
J 0
(-5790 3785);
DISPLAY 0.659574 (-5790 3785);
PAINT MONO (-5790 3785);
DISPLAY INVISIBLE (-5790 3785);
FORCEPROP 1 LASTPIN (-5800 3775) BN 30
J 0
(-5812 3783);
DISPLAY 0.489362 (-5812 3783);
PAINT GREEN (-5812 3783);
FORCEPROP 2 LAST CDS_LIB mstr_standard
J 0
(-5750 3775);
DISPLAY 0.723404 (-5750 3775);
PAINT MONO (-5750 3775);
DISPLAY INVISIBLE (-5750 3775);
FORCEPROP 1 LAST BODY_TYPE PLUMBING
J 0
(-5750 3825);
DISPLAY 0.872340 (-5750 3825);
PAINT GREEN (-5750 3825);
DISPLAY INVISIBLE (-5750 3825);
FORCEPROP 1 LAST HDL_TAP TRUE
J 0
(-5425 3650);
DISPLAY 0.872340 (-5425 3650);
DISPLAY INVISIBLE (-5425 3650);
FORCEPROP 1 LAST PATH I76
J 0
(-5752 3775);
DISPLAY 0.872340 (-5752 3775);
PAINT GREEN (-5752 3775);
DISPLAY INVISIBLE (-5752 3775);
FORCEADD TAP..1
(-5750 3825);
FORCEPROP 3 LASTPIN (-5800 3825) SIG_NAME M_A_CPU1_SB_DQ<31>
J 0
(-5790 3835);
DISPLAY 0.659574 (-5790 3835);
PAINT MONO (-5790 3835);
DISPLAY INVISIBLE (-5790 3835);
FORCEPROP 1 LASTPIN (-5800 3825) BN 31
J 0
(-5812 3833);
DISPLAY 0.489362 (-5812 3833);
PAINT GREEN (-5812 3833);
FORCEPROP 2 LAST CDS_LIB mstr_standard
J 0
(-5750 3825);
DISPLAY 0.723404 (-5750 3825);
PAINT MONO (-5750 3825);
DISPLAY INVISIBLE (-5750 3825);
FORCEPROP 1 LAST BODY_TYPE PLUMBING
J 0
(-5750 3875);
DISPLAY 0.872340 (-5750 3875);
PAINT GREEN (-5750 3875);
DISPLAY INVISIBLE (-5750 3875);
FORCEPROP 1 LAST HDL_TAP TRUE
J 0
(-5425 3700);
DISPLAY 0.872340 (-5425 3700);
DISPLAY INVISIBLE (-5425 3700);
FORCEPROP 1 LAST PATH I77
J 0
(-5752 3825);
DISPLAY 0.872340 (-5752 3825);
PAINT GREEN (-5752 3825);
DISPLAY INVISIBLE (-5752 3825);
FORCEADD TAP..1
(-5750 3975);
FORCEPROP 3 LASTPIN (-5800 3975) SIG_NAME M_A_CPU1_SA_DQ<1>
J 0
(-5790 3985);
DISPLAY 0.659574 (-5790 3985);
PAINT MONO (-5790 3985);
DISPLAY INVISIBLE (-5790 3985);
FORCEPROP 1 LASTPIN (-5800 3975) BN 1
J 0
(-5812 3983);
DISPLAY 0.489362 (-5812 3983);
PAINT GREEN (-5812 3983);
FORCEPROP 2 LAST CDS_LIB mstr_standard
J 0
(-5750 3975);
DISPLAY 0.723404 (-5750 3975);
PAINT MONO (-5750 3975);
DISPLAY INVISIBLE (-5750 3975);
FORCEPROP 1 LAST BODY_TYPE PLUMBING
J 0
(-5750 4025);
DISPLAY 0.872340 (-5750 4025);
PAINT GREEN (-5750 4025);
DISPLAY INVISIBLE (-5750 4025);
FORCEPROP 1 LAST HDL_TAP TRUE
J 0
(-5425 3850);
DISPLAY 0.872340 (-5425 3850);
DISPLAY INVISIBLE (-5425 3850);
FORCEPROP 1 LAST PATH I78
J 0
(-5752 3975);
DISPLAY 0.872340 (-5752 3975);
PAINT GREEN (-5752 3975);
DISPLAY INVISIBLE (-5752 3975);
FORCEADD TAP..1
(-5750 3925);
FORCEPROP 3 LASTPIN (-5800 3925) SIG_NAME M_A_CPU1_SA_DQ<0>
J 0
(-5790 3935);
DISPLAY 0.659574 (-5790 3935);
PAINT MONO (-5790 3935);
DISPLAY INVISIBLE (-5790 3935);
FORCEPROP 1 LASTPIN (-5800 3925) BN 0
J 0
(-5812 3933);
DISPLAY 0.489362 (-5812 3933);
PAINT GREEN (-5812 3933);
FORCEPROP 2 LAST CDS_LIB mstr_standard
J 0
(-5750 3925);
DISPLAY 0.723404 (-5750 3925);
PAINT MONO (-5750 3925);
DISPLAY INVISIBLE (-5750 3925);
FORCEPROP 1 LAST BODY_TYPE PLUMBING
J 0
(-5750 3975);
DISPLAY 0.872340 (-5750 3975);
PAINT GREEN (-5750 3975);
DISPLAY INVISIBLE (-5750 3975);
FORCEPROP 1 LAST HDL_TAP TRUE
J 0
(-5425 3800);
DISPLAY 0.872340 (-5425 3800);
DISPLAY INVISIBLE (-5425 3800);
FORCEPROP 1 LAST PATH I79
J 0
(-5752 3925);
DISPLAY 0.872340 (-5752 3925);
PAINT GREEN (-5752 3925);
DISPLAY INVISIBLE (-5752 3925);
FORCEADD VCC_CORE..1
(-8500 3550);
FORCEPROP 3 LASTPIN (-8500 3500) SIG_NAME P3V3_STBY\g
J 0
(-8490 3510);
DISPLAY 0.659574 (-8490 3510);
PAINT MONO (-8490 3510);
DISPLAY INVISIBLE (-8490 3510);
FORCEPROP 1 LAST HDL_POWER P3V3_STBY
J 1
(-8500 3600);
DISPLAY 0.489362 (-8500 3600);
PAINT GREEN (-8500 3600);
FORCEPROP 2 LAST CDS_LIB mstr_symbols
J 0
(-8500 3550);
PAINT MONO (-8500 3550);
DISPLAY INVISIBLE (-8500 3550);
FORCEPROP 1 LAST PATH I8
J 0
(-8450 3575);
DISPLAY 0.872340 (-8450 3575);
PAINT AQUA (-8450 3575);
DISPLAY INVISIBLE (-8450 3575);
FORCEPROP 0 LAST VOLTAGE 3.3
J 0
(-8775 3700);
DISPLAY 1.021277 (-8775 3700);
PAINT SKYBLUE (-8775 3700);
DISPLAY INVISIBLE (-8775 3700);
FORCEPROP 2 LAST ROOM PVCCINFAON_CPU1_CTRL
J 0
(-8500 3650);
DISPLAY 0.808511 (-8500 3650);
PAINT RED (-8500 3650);
DISPLAY INVISIBLE (-8500 3650);
FORCEADD TAP..1
(-5750 4075);
FORCEPROP 3 LASTPIN (-5800 4075) SIG_NAME M_A_CPU1_SA_DQ<3>
J 0
(-5790 4085);
DISPLAY 0.659574 (-5790 4085);
PAINT MONO (-5790 4085);
DISPLAY INVISIBLE (-5790 4085);
FORCEPROP 1 LASTPIN (-5800 4075) BN 3
J 0
(-5812 4083);
DISPLAY 0.489362 (-5812 4083);
PAINT GREEN (-5812 4083);
FORCEPROP 2 LAST CDS_LIB mstr_standard
J 0
(-5750 4075);
DISPLAY 0.723404 (-5750 4075);
PAINT MONO (-5750 4075);
DISPLAY INVISIBLE (-5750 4075);
FORCEPROP 1 LAST BODY_TYPE PLUMBING
J 0
(-5750 4125);
DISPLAY 0.872340 (-5750 4125);
PAINT GREEN (-5750 4125);
DISPLAY INVISIBLE (-5750 4125);
FORCEPROP 1 LAST HDL_TAP TRUE
J 0
(-5425 3950);
DISPLAY 0.872340 (-5425 3950);
DISPLAY INVISIBLE (-5425 3950);
FORCEPROP 1 LAST PATH I80
J 0
(-5752 4075);
DISPLAY 0.872340 (-5752 4075);
PAINT GREEN (-5752 4075);
DISPLAY INVISIBLE (-5752 4075);
FORCEADD TAP..1
(-5750 4125);
FORCEPROP 3 LASTPIN (-5800 4125) SIG_NAME M_A_CPU1_SA_DQ<4>
J 0
(-5790 4135);
DISPLAY 0.659574 (-5790 4135);
PAINT MONO (-5790 4135);
DISPLAY INVISIBLE (-5790 4135);
FORCEPROP 1 LASTPIN (-5800 4125) BN 4
J 0
(-5812 4133);
DISPLAY 0.489362 (-5812 4133);
PAINT GREEN (-5812 4133);
FORCEPROP 2 LAST CDS_LIB mstr_standard
J 0
(-5750 4125);
DISPLAY 0.723404 (-5750 4125);
PAINT MONO (-5750 4125);
DISPLAY INVISIBLE (-5750 4125);
FORCEPROP 1 LAST BODY_TYPE PLUMBING
J 0
(-5750 4175);
DISPLAY 0.872340 (-5750 4175);
PAINT GREEN (-5750 4175);
DISPLAY INVISIBLE (-5750 4175);
FORCEPROP 1 LAST HDL_TAP TRUE
J 0
(-5425 4000);
DISPLAY 0.872340 (-5425 4000);
DISPLAY INVISIBLE (-5425 4000);
FORCEPROP 1 LAST PATH I81
J 0
(-5752 4125);
DISPLAY 0.872340 (-5752 4125);
PAINT GREEN (-5752 4125);
DISPLAY INVISIBLE (-5752 4125);
FORCEADD TAP..1
(-5750 4025);
FORCEPROP 3 LASTPIN (-5800 4025) SIG_NAME M_A_CPU1_SA_DQ<2>
J 0
(-5790 4035);
DISPLAY 0.659574 (-5790 4035);
PAINT MONO (-5790 4035);
DISPLAY INVISIBLE (-5790 4035);
FORCEPROP 1 LASTPIN (-5800 4025) BN 2
J 0
(-5812 4033);
DISPLAY 0.489362 (-5812 4033);
PAINT GREEN (-5812 4033);
FORCEPROP 2 LAST CDS_LIB mstr_standard
J 0
(-5750 4025);
DISPLAY 0.723404 (-5750 4025);
PAINT MONO (-5750 4025);
DISPLAY INVISIBLE (-5750 4025);
FORCEPROP 1 LAST BODY_TYPE PLUMBING
J 0
(-5750 4075);
DISPLAY 0.872340 (-5750 4075);
PAINT GREEN (-5750 4075);
DISPLAY INVISIBLE (-5750 4075);
FORCEPROP 1 LAST HDL_TAP TRUE
J 0
(-5425 3900);
DISPLAY 0.872340 (-5425 3900);
DISPLAY INVISIBLE (-5425 3900);
FORCEPROP 1 LAST PATH I82
J 0
(-5752 4025);
DISPLAY 0.872340 (-5752 4025);
PAINT GREEN (-5752 4025);
DISPLAY INVISIBLE (-5752 4025);
FORCEADD OFFPAGE..3
(-5150 3875);
FORCEPROP 2 LAST $XR0 37 
J 0
(-4936 3875);
DISPLAY 0.638298 (-4936 3875);
PAINT MONO (-4936 3875);
FORCEPROP 2 LAST CDS_LIB mstr_standard
J 0
(-5150 3875);
DISPLAY 0.723404 (-5150 3875);
PAINT MONO (-5150 3875);
DISPLAY INVISIBLE (-5150 3875);
FORCEPROP 1 LAST OFFPAGE TRUE
J 0
(-4825 3750);
DISPLAY 0.872340 (-4825 3750);
PAINT GREEN (-4825 3750);
DISPLAY INVISIBLE (-4825 3750);
FORCEPROP 1 LAST COMMENT_BODY TRUE
J 0
(-5200 3775);
DISPLAY 0.872340 (-5200 3775);
PAINT GREEN (-5200 3775);
DISPLAY INVISIBLE (-5200 3775);
FORCEPROP 2 LAST PATH I83
J 0
(-4825 3925);
DISPLAY 1.021277 (-4825 3925);
DISPLAY INVISIBLE (-4825 3925);
FORCEADD TAP..1
R 2
(-7450 4775);
FORCEPROP 3 LASTPIN (-7400 4775) SIG_NAME M_A_CPU1_SB_CA<0>
J 0
(-7390 4785);
DISPLAY 0.659574 (-7390 4785);
PAINT MONO (-7390 4785);
DISPLAY INVISIBLE (-7390 4785);
FORCEPROP 1 LASTPIN (-7400 4775) BN 0
J 2
(-7388 4783);
DISPLAY 0.489362 (-7388 4783);
PAINT GREEN (-7388 4783);
FORCEPROP 2 LAST CDS_LIB mstr_standard
J 0
(-7450 4775);
DISPLAY 0.723404 (-7450 4775);
PAINT MONO (-7450 4775);
DISPLAY INVISIBLE (-7450 4775);
FORCEPROP 1 LAST BODY_TYPE PLUMBING
J 2
(-7450 4825);
DISPLAY 0.872340 (-7450 4825);
PAINT GREEN (-7450 4825);
DISPLAY INVISIBLE (-7450 4825);
FORCEPROP 1 LAST HDL_TAP TRUE
J 2
(-7775 4650);
DISPLAY 0.872340 (-7775 4650);
DISPLAY INVISIBLE (-7775 4650);
FORCEPROP 1 LAST PATH I85
J 2
(-7448 4775);
DISPLAY 0.872340 (-7448 4775);
PAINT GREEN (-7448 4775);
DISPLAY INVISIBLE (-7448 4775);
FORCEADD TAP..1
R 2
(-7450 4825);
FORCEPROP 3 LASTPIN (-7400 4825) SIG_NAME M_A_CPU1_SB_CA<1>
J 0
(-7390 4835);
DISPLAY 0.659574 (-7390 4835);
PAINT MONO (-7390 4835);
DISPLAY INVISIBLE (-7390 4835);
FORCEPROP 1 LASTPIN (-7400 4825) BN 1
J 2
(-7388 4833);
DISPLAY 0.489362 (-7388 4833);
PAINT GREEN (-7388 4833);
FORCEPROP 2 LAST CDS_LIB mstr_standard
J 0
(-7450 4825);
DISPLAY 0.723404 (-7450 4825);
PAINT MONO (-7450 4825);
DISPLAY INVISIBLE (-7450 4825);
FORCEPROP 1 LAST BODY_TYPE PLUMBING
J 2
(-7450 4875);
DISPLAY 0.872340 (-7450 4875);
PAINT GREEN (-7450 4875);
DISPLAY INVISIBLE (-7450 4875);
FORCEPROP 1 LAST HDL_TAP TRUE
J 2
(-7775 4700);
DISPLAY 0.872340 (-7775 4700);
DISPLAY INVISIBLE (-7775 4700);
FORCEPROP 1 LAST PATH I86
J 2
(-7448 4825);
DISPLAY 0.872340 (-7448 4825);
PAINT GREEN (-7448 4825);
DISPLAY INVISIBLE (-7448 4825);
FORCEADD TAP..1
R 2
(-7450 4875);
FORCEPROP 3 LASTPIN (-7400 4875) SIG_NAME M_A_CPU1_SB_CA<2>
J 0
(-7390 4885);
DISPLAY 0.659574 (-7390 4885);
PAINT MONO (-7390 4885);
DISPLAY INVISIBLE (-7390 4885);
FORCEPROP 1 LASTPIN (-7400 4875) BN 2
J 2
(-7388 4883);
DISPLAY 0.489362 (-7388 4883);
PAINT GREEN (-7388 4883);
FORCEPROP 2 LAST CDS_LIB mstr_standard
J 0
(-7450 4875);
DISPLAY 0.723404 (-7450 4875);
PAINT MONO (-7450 4875);
DISPLAY INVISIBLE (-7450 4875);
FORCEPROP 1 LAST BODY_TYPE PLUMBING
J 2
(-7450 4925);
DISPLAY 0.872340 (-7450 4925);
PAINT GREEN (-7450 4925);
DISPLAY INVISIBLE (-7450 4925);
FORCEPROP 1 LAST HDL_TAP TRUE
J 2
(-7775 4750);
DISPLAY 0.872340 (-7775 4750);
DISPLAY INVISIBLE (-7775 4750);
FORCEPROP 1 LAST PATH I87
J 2
(-7448 4875);
DISPLAY 0.872340 (-7448 4875);
PAINT GREEN (-7448 4875);
DISPLAY INVISIBLE (-7448 4875);
FORCEADD TAP..1
R 2
(-7450 4925);
FORCEPROP 3 LASTPIN (-7400 4925) SIG_NAME M_A_CPU1_SB_CA<3>
J 0
(-7390 4935);
DISPLAY 0.659574 (-7390 4935);
PAINT MONO (-7390 4935);
DISPLAY INVISIBLE (-7390 4935);
FORCEPROP 1 LASTPIN (-7400 4925) BN 3
J 2
(-7388 4933);
DISPLAY 0.489362 (-7388 4933);
PAINT GREEN (-7388 4933);
FORCEPROP 2 LAST CDS_LIB mstr_standard
J 0
(-7450 4925);
DISPLAY 0.723404 (-7450 4925);
PAINT MONO (-7450 4925);
DISPLAY INVISIBLE (-7450 4925);
FORCEPROP 1 LAST BODY_TYPE PLUMBING
J 2
(-7450 4975);
DISPLAY 0.872340 (-7450 4975);
PAINT GREEN (-7450 4975);
DISPLAY INVISIBLE (-7450 4975);
FORCEPROP 1 LAST HDL_TAP TRUE
J 2
(-7775 4800);
DISPLAY 0.872340 (-7775 4800);
DISPLAY INVISIBLE (-7775 4800);
FORCEPROP 1 LAST PATH I88
J 2
(-7448 4925);
DISPLAY 0.872340 (-7448 4925);
PAINT GREEN (-7448 4925);
DISPLAY INVISIBLE (-7448 4925);
FORCEADD TAP..1
R 2
(-7450 4975);
FORCEPROP 3 LASTPIN (-7400 4975) SIG_NAME M_A_CPU1_SB_CA<4>
J 0
(-7390 4985);
DISPLAY 0.659574 (-7390 4985);
PAINT MONO (-7390 4985);
DISPLAY INVISIBLE (-7390 4985);
FORCEPROP 1 LASTPIN (-7400 4975) BN 4
J 2
(-7388 4983);
DISPLAY 0.489362 (-7388 4983);
PAINT GREEN (-7388 4983);
FORCEPROP 2 LAST CDS_LIB mstr_standard
J 0
(-7450 4975);
DISPLAY 0.723404 (-7450 4975);
PAINT MONO (-7450 4975);
DISPLAY INVISIBLE (-7450 4975);
FORCEPROP 1 LAST BODY_TYPE PLUMBING
J 2
(-7450 5025);
DISPLAY 0.872340 (-7450 5025);
PAINT GREEN (-7450 5025);
DISPLAY INVISIBLE (-7450 5025);
FORCEPROP 1 LAST HDL_TAP TRUE
J 2
(-7775 4850);
DISPLAY 0.872340 (-7775 4850);
DISPLAY INVISIBLE (-7775 4850);
FORCEPROP 1 LAST PATH I89
J 2
(-7448 4975);
DISPLAY 0.872340 (-7448 4975);
PAINT GREEN (-7448 4975);
DISPLAY INVISIBLE (-7448 4975);
FORCEADD OFFPAGE..1
(-8050 3175);
FORCEPROP 2 LAST $XR0 37 
J 0
(-8271 3175);
DISPLAY 0.638298 (-8271 3175);
PAINT MONO (-8271 3175);
FORCEPROP 2 LAST CDS_LIB mstr_standard
J 0
(-8050 3175);
DISPLAY 0.808511 (-8050 3175);
DISPLAY INVISIBLE (-8050 3175);
FORCEPROP 1 LAST OFFPAGE TRUE
J 0
(-7725 3050);
DISPLAY 0.872340 (-7725 3050);
PAINT GREEN (-7725 3050);
DISPLAY INVISIBLE (-7725 3050);
FORCEPROP 1 LAST COMMENT_BODY TRUE
J 0
(-7925 3075);
DISPLAY 0.872340 (-7925 3075);
PAINT GREEN (-7925 3075);
DISPLAY INVISIBLE (-7925 3075);
FORCEPROP 2 LAST PATH I9
J 0
(-8300 3225);
DISPLAY 1.021277 (-8300 3225);
DISPLAY INVISIBLE (-8300 3225);
FORCEADD TAP..1
R 2
(-7450 5025);
FORCEPROP 3 LASTPIN (-7400 5025) SIG_NAME M_A_CPU1_SB_CA<5>
J 0
(-7390 5035);
DISPLAY 0.659574 (-7390 5035);
PAINT MONO (-7390 5035);
DISPLAY INVISIBLE (-7390 5035);
FORCEPROP 1 LASTPIN (-7400 5025) BN 5
J 2
(-7388 5033);
DISPLAY 0.489362 (-7388 5033);
PAINT GREEN (-7388 5033);
FORCEPROP 2 LAST CDS_LIB mstr_standard
J 0
(-7450 5025);
DISPLAY 0.723404 (-7450 5025);
PAINT MONO (-7450 5025);
DISPLAY INVISIBLE (-7450 5025);
FORCEPROP 1 LAST BODY_TYPE PLUMBING
J 2
(-7450 5075);
DISPLAY 0.872340 (-7450 5075);
PAINT GREEN (-7450 5075);
DISPLAY INVISIBLE (-7450 5075);
FORCEPROP 1 LAST HDL_TAP TRUE
J 2
(-7775 4900);
DISPLAY 0.872340 (-7775 4900);
DISPLAY INVISIBLE (-7775 4900);
FORCEPROP 1 LAST PATH I90
J 2
(-7448 5025);
DISPLAY 0.872340 (-7448 5025);
PAINT GREEN (-7448 5025);
DISPLAY INVISIBLE (-7448 5025);
FORCEADD TAP..1
R 2
(-7450 5075);
FORCEPROP 3 LASTPIN (-7400 5075) SIG_NAME M_A_CPU1_SB_CA<6>
J 0
(-7390 5085);
DISPLAY 0.659574 (-7390 5085);
PAINT MONO (-7390 5085);
DISPLAY INVISIBLE (-7390 5085);
FORCEPROP 1 LASTPIN (-7400 5075) BN 6
J 2
(-7388 5083);
DISPLAY 0.489362 (-7388 5083);
PAINT GREEN (-7388 5083);
FORCEPROP 2 LAST CDS_LIB mstr_standard
J 0
(-7450 5075);
DISPLAY 0.723404 (-7450 5075);
PAINT MONO (-7450 5075);
DISPLAY INVISIBLE (-7450 5075);
FORCEPROP 1 LAST BODY_TYPE PLUMBING
J 2
(-7450 5125);
DISPLAY 0.872340 (-7450 5125);
PAINT GREEN (-7450 5125);
DISPLAY INVISIBLE (-7450 5125);
FORCEPROP 1 LAST HDL_TAP TRUE
J 2
(-7775 4950);
DISPLAY 0.872340 (-7775 4950);
DISPLAY INVISIBLE (-7775 4950);
FORCEPROP 1 LAST PATH I91
J 2
(-7448 5075);
DISPLAY 0.872340 (-7448 5075);
PAINT GREEN (-7448 5075);
DISPLAY INVISIBLE (-7448 5075);
FORCEADD TAP..1
R 2
(-7450 5225);
FORCEPROP 3 LASTPIN (-7400 5225) SIG_NAME M_A_CPU1_SA_CA<1>
J 0
(-7390 5235);
DISPLAY 0.659574 (-7390 5235);
PAINT MONO (-7390 5235);
DISPLAY INVISIBLE (-7390 5235);
FORCEPROP 1 LASTPIN (-7400 5225) BN 1
J 2
(-7388 5233);
DISPLAY 0.489362 (-7388 5233);
PAINT GREEN (-7388 5233);
FORCEPROP 2 LAST CDS_LIB mstr_standard
J 0
(-7450 5225);
DISPLAY 0.723404 (-7450 5225);
PAINT MONO (-7450 5225);
DISPLAY INVISIBLE (-7450 5225);
FORCEPROP 1 LAST BODY_TYPE PLUMBING
J 2
(-7450 5275);
DISPLAY 0.872340 (-7450 5275);
PAINT GREEN (-7450 5275);
DISPLAY INVISIBLE (-7450 5275);
FORCEPROP 1 LAST HDL_TAP TRUE
J 2
(-7775 5100);
DISPLAY 0.872340 (-7775 5100);
DISPLAY INVISIBLE (-7775 5100);
FORCEPROP 1 LAST PATH I92
J 2
(-7448 5225);
DISPLAY 0.872340 (-7448 5225);
PAINT GREEN (-7448 5225);
DISPLAY INVISIBLE (-7448 5225);
FORCEADD TAP..1
R 2
(-7450 5175);
FORCEPROP 3 LASTPIN (-7400 5175) SIG_NAME M_A_CPU1_SA_CA<0>
J 0
(-7390 5185);
DISPLAY 0.659574 (-7390 5185);
PAINT MONO (-7390 5185);
DISPLAY INVISIBLE (-7390 5185);
FORCEPROP 1 LASTPIN (-7400 5175) BN 0
J 2
(-7388 5183);
DISPLAY 0.489362 (-7388 5183);
PAINT GREEN (-7388 5183);
FORCEPROP 2 LAST CDS_LIB mstr_standard
J 0
(-7450 5175);
DISPLAY 0.723404 (-7450 5175);
PAINT MONO (-7450 5175);
DISPLAY INVISIBLE (-7450 5175);
FORCEPROP 1 LAST BODY_TYPE PLUMBING
J 2
(-7450 5225);
DISPLAY 0.872340 (-7450 5225);
PAINT GREEN (-7450 5225);
DISPLAY INVISIBLE (-7450 5225);
FORCEPROP 1 LAST HDL_TAP TRUE
J 2
(-7775 5050);
DISPLAY 0.872340 (-7775 5050);
DISPLAY INVISIBLE (-7775 5050);
FORCEPROP 1 LAST PATH I93
J 2
(-7448 5175);
DISPLAY 0.872340 (-7448 5175);
PAINT GREEN (-7448 5175);
DISPLAY INVISIBLE (-7448 5175);
FORCEADD TAP..1
R 2
(-7450 5275);
FORCEPROP 3 LASTPIN (-7400 5275) SIG_NAME M_A_CPU1_SA_CA<2>
J 0
(-7390 5285);
DISPLAY 0.659574 (-7390 5285);
PAINT MONO (-7390 5285);
DISPLAY INVISIBLE (-7390 5285);
FORCEPROP 1 LASTPIN (-7400 5275) BN 2
J 2
(-7388 5283);
DISPLAY 0.489362 (-7388 5283);
PAINT GREEN (-7388 5283);
FORCEPROP 2 LAST CDS_LIB mstr_standard
J 0
(-7450 5275);
DISPLAY 0.723404 (-7450 5275);
PAINT MONO (-7450 5275);
DISPLAY INVISIBLE (-7450 5275);
FORCEPROP 1 LAST BODY_TYPE PLUMBING
J 2
(-7450 5325);
DISPLAY 0.872340 (-7450 5325);
PAINT GREEN (-7450 5325);
DISPLAY INVISIBLE (-7450 5325);
FORCEPROP 1 LAST HDL_TAP TRUE
J 2
(-7775 5150);
DISPLAY 0.872340 (-7775 5150);
DISPLAY INVISIBLE (-7775 5150);
FORCEPROP 1 LAST PATH I94
J 2
(-7448 5275);
DISPLAY 0.872340 (-7448 5275);
PAINT GREEN (-7448 5275);
DISPLAY INVISIBLE (-7448 5275);
FORCEADD TAP..1
R 2
(-7450 5325);
FORCEPROP 3 LASTPIN (-7400 5325) SIG_NAME M_A_CPU1_SA_CA<3>
J 0
(-7390 5335);
DISPLAY 0.659574 (-7390 5335);
PAINT MONO (-7390 5335);
DISPLAY INVISIBLE (-7390 5335);
FORCEPROP 1 LASTPIN (-7400 5325) BN 3
J 2
(-7388 5333);
DISPLAY 0.489362 (-7388 5333);
PAINT GREEN (-7388 5333);
FORCEPROP 2 LAST CDS_LIB mstr_standard
J 0
(-7450 5325);
DISPLAY 0.723404 (-7450 5325);
PAINT MONO (-7450 5325);
DISPLAY INVISIBLE (-7450 5325);
FORCEPROP 1 LAST BODY_TYPE PLUMBING
J 2
(-7450 5375);
DISPLAY 0.872340 (-7450 5375);
PAINT GREEN (-7450 5375);
DISPLAY INVISIBLE (-7450 5375);
FORCEPROP 1 LAST HDL_TAP TRUE
J 2
(-7775 5200);
DISPLAY 0.872340 (-7775 5200);
DISPLAY INVISIBLE (-7775 5200);
FORCEPROP 1 LAST PATH I95
J 2
(-7448 5325);
DISPLAY 0.872340 (-7448 5325);
PAINT GREEN (-7448 5325);
DISPLAY INVISIBLE (-7448 5325);
FORCEADD TAP..1
R 2
(-7450 5375);
FORCEPROP 3 LASTPIN (-7400 5375) SIG_NAME M_A_CPU1_SA_CA<4>
J 0
(-7390 5385);
DISPLAY 0.659574 (-7390 5385);
PAINT MONO (-7390 5385);
DISPLAY INVISIBLE (-7390 5385);
FORCEPROP 1 LASTPIN (-7400 5375) BN 4
J 2
(-7388 5383);
DISPLAY 0.489362 (-7388 5383);
PAINT GREEN (-7388 5383);
FORCEPROP 2 LAST CDS_LIB mstr_standard
J 0
(-7450 5375);
DISPLAY 0.723404 (-7450 5375);
PAINT MONO (-7450 5375);
DISPLAY INVISIBLE (-7450 5375);
FORCEPROP 1 LAST BODY_TYPE PLUMBING
J 2
(-7450 5425);
DISPLAY 0.872340 (-7450 5425);
PAINT GREEN (-7450 5425);
DISPLAY INVISIBLE (-7450 5425);
FORCEPROP 1 LAST HDL_TAP TRUE
J 2
(-7775 5250);
DISPLAY 0.872340 (-7775 5250);
DISPLAY INVISIBLE (-7775 5250);
FORCEPROP 1 LAST PATH I96
J 2
(-7448 5375);
DISPLAY 0.872340 (-7448 5375);
PAINT GREEN (-7448 5375);
DISPLAY INVISIBLE (-7448 5375);
FORCEADD TAP..1
R 2
(-7450 5425);
FORCEPROP 3 LASTPIN (-7400 5425) SIG_NAME M_A_CPU1_SA_CA<5>
J 0
(-7390 5435);
DISPLAY 0.659574 (-7390 5435);
PAINT MONO (-7390 5435);
DISPLAY INVISIBLE (-7390 5435);
FORCEPROP 1 LASTPIN (-7400 5425) BN 5
J 2
(-7388 5433);
DISPLAY 0.489362 (-7388 5433);
PAINT GREEN (-7388 5433);
FORCEPROP 2 LAST CDS_LIB mstr_standard
J 0
(-7450 5425);
DISPLAY 0.723404 (-7450 5425);
PAINT MONO (-7450 5425);
DISPLAY INVISIBLE (-7450 5425);
FORCEPROP 1 LAST BODY_TYPE PLUMBING
J 2
(-7450 5475);
DISPLAY 0.872340 (-7450 5475);
PAINT GREEN (-7450 5475);
DISPLAY INVISIBLE (-7450 5475);
FORCEPROP 1 LAST HDL_TAP TRUE
J 2
(-7775 5300);
DISPLAY 0.872340 (-7775 5300);
DISPLAY INVISIBLE (-7775 5300);
FORCEPROP 1 LAST PATH I97
J 2
(-7448 5425);
DISPLAY 0.872340 (-7448 5425);
PAINT GREEN (-7448 5425);
DISPLAY INVISIBLE (-7448 5425);
FORCEADD TAP..1
R 2
(-7450 5475);
FORCEPROP 3 LASTPIN (-7400 5475) SIG_NAME M_A_CPU1_SA_CA<6>
J 0
(-7390 5485);
DISPLAY 0.659574 (-7390 5485);
PAINT MONO (-7390 5485);
DISPLAY INVISIBLE (-7390 5485);
FORCEPROP 1 LASTPIN (-7400 5475) BN 6
J 2
(-7388 5483);
DISPLAY 0.489362 (-7388 5483);
PAINT GREEN (-7388 5483);
FORCEPROP 2 LAST CDS_LIB mstr_standard
J 0
(-7450 5475);
DISPLAY 0.723404 (-7450 5475);
PAINT MONO (-7450 5475);
DISPLAY INVISIBLE (-7450 5475);
FORCEPROP 1 LAST BODY_TYPE PLUMBING
J 2
(-7450 5525);
DISPLAY 0.872340 (-7450 5525);
PAINT GREEN (-7450 5525);
DISPLAY INVISIBLE (-7450 5525);
FORCEPROP 1 LAST HDL_TAP TRUE
J 2
(-7775 5350);
DISPLAY 0.872340 (-7775 5350);
DISPLAY INVISIBLE (-7775 5350);
FORCEPROP 1 LAST PATH I98
J 2
(-7448 5475);
DISPLAY 0.872340 (-7448 5475);
PAINT GREEN (-7448 5475);
DISPLAY INVISIBLE (-7448 5475);
FORCEADD TAP..1
(-5750 4225);
FORCEPROP 3 LASTPIN (-5800 4225) SIG_NAME M_A_CPU1_SA_DQ<6>
J 0
(-5790 4235);
DISPLAY 0.659574 (-5790 4235);
PAINT MONO (-5790 4235);
DISPLAY INVISIBLE (-5790 4235);
FORCEPROP 1 LASTPIN (-5800 4225) BN 6
J 0
(-5812 4233);
DISPLAY 0.489362 (-5812 4233);
PAINT GREEN (-5812 4233);
FORCEPROP 2 LAST CDS_LIB mstr_standard
J 0
(-5750 4225);
DISPLAY 0.723404 (-5750 4225);
PAINT MONO (-5750 4225);
DISPLAY INVISIBLE (-5750 4225);
FORCEPROP 1 LAST BODY_TYPE PLUMBING
J 0
(-5750 4275);
DISPLAY 0.872340 (-5750 4275);
PAINT GREEN (-5750 4275);
DISPLAY INVISIBLE (-5750 4275);
FORCEPROP 1 LAST HDL_TAP TRUE
J 0
(-5425 4100);
DISPLAY 0.872340 (-5425 4100);
DISPLAY INVISIBLE (-5425 4100);
FORCEPROP 1 LAST PATH I99
J 0
(-5752 4225);
DISPLAY 0.872340 (-5752 4225);
PAINT GREEN (-5752 4225);
DISPLAY INVISIBLE (-5752 4225);
FORCEADD QUANTA_TITLE_BLOCK_C..1
(-100 100);
FORCEPROP 0 LAST CDS_CON_LAST_MODIFIED Fri Mar 11 14:53:01 2022
J 0
(-1985 115);
DISPLAY INVISIBLE (-1985 115);
FORCEPROP 1 LAST CUSTOM_TXT_CDS <CON_LAST_MODIFIED>
J 0
(-1985 115);
DISPLAY 0.978723 (-1985 115);
FORCEPROP 2 LAST CUSTOM_TXT_CDS <XR_PAGE_TITLE>
J 0
(-7990 5350);
DISPLAY 0.638298 (-7990 5350);
PAINT PINK (-7990 5350);
DISPLAY INVISIBLE (-7990 5350);
FORCEPROP 1 LAST CUSTOM_TXT_CDS <NAME_2>
J 0
(-3275 150);
FORCEPROP 1 LAST CUSTOM_TXT_CDS <NAME_1>
J 0
(-3275 275);
FORCEPROP 1 LAST CUSTOM_TXT_CDS <Q_NUMBER>
J 0
(-1503 203);
DISPLAY 1.212766 (-1503 203);
FORCEPROP 1 LAST CUSTOM_TXT_CDS <Q_PROJ>
J 0
(-2482 202);
DISPLAY 1.212766 (-2482 202);
FORCEPROP 1 LAST CUSTOM_TXT_CDS <Q_REV>
J 0
(-284 203);
DISPLAY 1.212766 (-284 203);
FORCEPROP 1 LAST CUSTOM_TXT_CDS <CON_PAGE_NUM> OF <CON_TOTAL_PAGES>
J 0
(-546 118);
DISPLAY 0.978723 (-546 118);
FORCEPROP 1 LAST Q_DEPT BU9
J 1
(-3863 149);
DISPLAY 1.957447 (-3863 149);
PAINT GREEN (-3863 149);
FORCEPROP 1 LAST Q_TITLE DDR5 - CPU1 CHA
J 0
(-9400 150);
DISPLAY 2.446809 (-9400 150);
PAINT GREEN (-9400 150);
FORCEPROP 2 LAST CDS_LIB pure_quanta
J 0
(-100 100);
DISPLAY INVISIBLE (-100 100);
FORCEPROP 1 LAST CDS_LMAN_SYM_OUTLINE -9475,6775,100,-125
J 0
(-100 100);
DISPLAY 0.468085 (-100 100);
PAINT GREEN (-100 100);
DISPLAY INVISIBLE (-100 100);
FORCEPROP 2 LAST PAGE_BORDER TRUE
J 0
(-7990 5350);
DISPLAY 0.638298 (-7990 5350);
PAINT PINK (-7990 5350);
DISPLAY INVISIBLE (-7990 5350);
FORCEPROP 1 LAST COMMENT_BODY TRUE
J 0
(-88 87);
DISPLAY 0.978723 (-88 87);
PAINT GREEN (-88 87);
DISPLAY INVISIBLE (-88 87);
FORCEPROP 2 LAST CDS_XR_PAGE_TITLE CR-97 : @T6G_MB_LIB.T6G(SCH_1):PAGE97
J 0
(-7990 5350);
DISPLAY 0.638298 (-7990 5350);
PAINT PINK (-7990 5350);
DISPLAY INVISIBLE (-7990 5350);
FORCEADD DNS..2
(-8250 2375);
PAINT RED (-8250 2375);
FORCEPROP 2 LAST CDS_LIB mstr_misc
J 0
(-8250 2375);
DISPLAY INVISIBLE (-8250 2375);
FORCEPROP 1 LAST COMMENT_BODY TRUE
R 1
J 0
(-8175 2150);
DISPLAY 0.872340 (-8175 2150);
PAINT PEACH (-8175 2150);
DISPLAY INVISIBLE (-8175 2150);
WIRE 17 -1 (-5700 5500)(-5700 5450);
WIRE 17 -1 (-5700 5525)(-5700 5500);
WIRE 17 -1 (-5700 5450)(-5700 5400);
WIRE 17 -1 (-5700 5400)(-5700 5350);
WIRE 17 -1 (-5700 5525)(-5200 5525);
FORCEPROP 2 LAST SIG_NAME M_A_CPU1_SA_DQ<31:0>
J 2
(-5200 5535);
DISPLAY 0.489362 (-5200 5535);
WIRE 17 -1 (-7500 4100)(-7500 4050);
WIRE 17 -1 (-7500 4100)(-7500 4125);
WIRE 17 -1 (-7500 4000)(-7500 4050);
WIRE 17 -1 (-7500 4000)(-7500 3950);
WIRE 17 -1 (-7500 4125)(-8000 4125);
FORCEPROP 2 LAST SIG_NAME M_A_CPU1_SA_CB<7:0>
J 0
(-8000 4135);
DISPLAY 0.489362 (-8000 4135);
WIRE 17 -1 (-7500 3900)(-7500 3950);
WIRE 17 -1 (-7500 3850)(-7500 3900);
WIRE 17 -1 (-7500 3800)(-7500 3850);
WIRE 17 -1 (-7500 3750)(-7500 3800);
WIRE 17 -1 (-7500 3650)(-7500 3675);
WIRE 17 -1 (-7500 3650)(-7500 3600);
WIRE 17 -1 (-7500 3675)(-8000 3675);
FORCEPROP 2 LAST SIG_NAME M_A_CPU1_SB_CB<7:0>
J 0
(-8000 3685);
DISPLAY 0.489362 (-8000 3685);
WIRE 17 -1 (-7500 4800)(-7500 4850);
WIRE 17 -1 (-7500 4850)(-7500 4900);
WIRE 17 -1 (-7500 4900)(-7500 4950);
WIRE 17 -1 (-7500 4950)(-7500 5000);
WIRE 17 -1 (-7500 5000)(-7500 5050);
WIRE 17 -1 (-7500 5050)(-7500 5100);
WIRE 17 -1 (-7500 5100)(-7500 5125);
WIRE 17 -1 (-7500 5125)(-8000 5125);
FORCEPROP 2 LAST SIG_NAME M_A_CPU1_SB_CA<6:0>
J 0
(-8000 5135);
DISPLAY 0.489362 (-8000 5135);
WIRE 17 -1 (-7500 5250)(-7500 5300);
WIRE 17 -1 (-7500 5200)(-7500 5250);
WIRE 17 -1 (-7500 5300)(-7500 5350);
WIRE 17 -1 (-7500 5350)(-7500 5400);
WIRE 17 -1 (-7500 5400)(-7500 5450);
WIRE 17 -1 (-7500 5450)(-7500 5500);
WIRE 17 -1 (-7500 5500)(-7500 5525);
WIRE 17 -1 (-7500 5525)(-8000 5525);
FORCEPROP 2 LAST SIG_NAME M_A_CPU1_SA_CA<6:0>
J 0
(-8000 5535);
DISPLAY 0.489362 (-8000 5535);
WIRE 17 -1 (-7500 3550)(-7500 3600);
WIRE 17 -1 (-7500 3550)(-7500 3500);
WIRE 17 -1 (-7500 3450)(-7500 3500);
WIRE 17 -1 (-7500 3400)(-7500 3450);
WIRE 17 -1 (-7500 3350)(-7500 3400);
WIRE 17 -1 (-7500 3300)(-7500 3350);
WIRE 17 -1 (-5700 5350)(-5700 5300);
WIRE 17 -1 (-5700 5300)(-5700 5250);
WIRE 17 -1 (-5700 5250)(-5700 5200);
WIRE 17 -1 (-5700 5200)(-5700 5150);
WIRE 17 -1 (-5700 5150)(-5700 5100);
WIRE 17 -1 (-5700 5100)(-5700 5050);
WIRE 17 -1 (-5700 5050)(-5700 5000);
WIRE 17 -1 (-5700 5000)(-5700 4950);
WIRE 17 -1 (-5700 4950)(-5700 4900);
WIRE 17 -1 (-5700 4900)(-5700 4850);
WIRE 17 -1 (-5700 4850)(-5700 4800);
WIRE 17 -1 (-5700 4800)(-5700 4750);
WIRE 17 -1 (-5700 4700)(-5700 4750);
WIRE 17 -1 (-5700 4650)(-5700 4700);
WIRE 17 -1 (-5700 4600)(-5700 4650);
WIRE 17 -1 (-5700 4550)(-5700 4600);
WIRE 17 -1 (-5700 4550)(-5700 4500);
WIRE 17 -1 (-5700 4500)(-5700 4450);
WIRE 17 -1 (-5700 4450)(-5700 4400);
WIRE 17 -1 (-5700 4400)(-5700 4350);
WIRE 17 -1 (-5700 4350)(-5700 4300);
WIRE 17 -1 (-5700 4300)(-5700 4250);
WIRE 17 -1 (-5700 4250)(-5700 4200);
WIRE 17 -1 (-5700 4200)(-5700 4150);
WIRE 17 -1 (-5700 4100)(-5700 4150);
WIRE 17 -1 (-5700 4050)(-5700 4100);
WIRE 17 -1 (-5700 4000)(-5700 4050);
WIRE 17 -1 (-5700 3950)(-5700 4000);
WIRE 17 -1 (-5700 3850)(-5700 3800);
WIRE 17 -1 (-5700 3875)(-5700 3850);
WIRE 17 -1 (-5700 3800)(-5700 3750);
WIRE 17 -1 (-5700 3750)(-5700 3700);
WIRE 17 -1 (-5700 3875)(-5200 3875);
FORCEPROP 2 LAST SIG_NAME M_A_CPU1_SB_DQ<31:0>
J 2
(-5200 3885);
DISPLAY 0.489362 (-5200 3885);
WIRE 17 -1 (-5700 3700)(-5700 3650);
WIRE 17 -1 (-5700 3650)(-5700 3600);
WIRE 17 -1 (-5700 3600)(-5700 3550);
WIRE 17 -1 (-5700 3550)(-5700 3500);
WIRE 17 -1 (-5700 3500)(-5700 3450);
WIRE 17 -1 (-5700 3450)(-5700 3400);
WIRE 17 -1 (-5700 3400)(-5700 3350);
WIRE 17 -1 (-5700 3350)(-5700 3300);
WIRE 17 -1 (-5700 3300)(-5700 3250);
WIRE 17 -1 (-5700 3250)(-5700 3200);
WIRE 17 -1 (-5700 3200)(-5700 3150);
WIRE 17 -1 (-5700 3150)(-5700 3100);
WIRE 17 -1 (-5700 3050)(-5700 3100);
WIRE 17 -1 (-5700 3000)(-5700 3050);
WIRE 17 -1 (-5700 2950)(-5700 3000);
WIRE 17 -1 (-5700 2900)(-5700 2950);
WIRE 17 -1 (-5700 2900)(-5700 2850);
WIRE 17 -1 (-5700 2850)(-5700 2800);
WIRE 17 -1 (-5700 2800)(-5700 2750);
WIRE 17 -1 (-5700 2750)(-5700 2700);
WIRE 17 -1 (-5700 2700)(-5700 2650);
WIRE 17 -1 (-5700 2650)(-5700 2600);
WIRE 17 -1 (-5700 2600)(-5700 2550);
WIRE 17 -1 (-5700 2550)(-5700 2500);
WIRE 17 -1 (-5700 2450)(-5700 2500);
WIRE 17 -1 (-5700 2400)(-5700 2450);
WIRE 17 -1 (-5700 2350)(-5700 2400);
WIRE 17 -1 (-5700 2300)(-5700 2350);
WIRE 17 -1 (-2975 4375)(-2975 4275);
WIRE 17 -1 (-2975 4475)(-2975 4375);
WIRE 17 -1 (-2975 4275)(-2975 4175);
WIRE 17 -1 (-2975 4075)(-2975 4175);
WIRE 17 -1 (-2975 4575)(-2975 4475);
WIRE 17 -1 (-2975 4600)(-2975 4575);
WIRE 17 -1 (-2975 3975)(-2975 4075);
WIRE 17 -1 (-2975 3875)(-2975 3975);
WIRE 17 -1 (-2975 4600)(-2475 4600);
FORCEPROP 2 LAST SIG_NAME M_A_CPU1_SA_DQS_DN<9:0>
J 0
(-3010 4610);
DISPLAY 0.489362 (-3010 4610);
WIRE 17 -1 (-3175 4325)(-3175 4225);
WIRE 17 -1 (-3175 4425)(-3175 4325);
WIRE 17 -1 (-3175 4125)(-3175 4225);
WIRE 17 -1 (-3175 4025)(-3175 4125);
WIRE 17 -1 (-3175 4525)(-3175 4425);
WIRE 17 -1 (-3175 4625)(-3175 4525);
WIRE 17 -1 (-3175 3925)(-3175 4025);
WIRE 17 -1 (-3175 3925)(-3175 3825);
WIRE 17 -1 (-3175 4650)(-3175 4625);
WIRE 17 -1 (-3175 4650)(-2475 4650);
FORCEPROP 2 LAST SIG_NAME M_A_CPU1_SA_DQS_DP<9:0>
J 0
(-3010 4660);
DISPLAY 0.489362 (-3010 4660);
WIRE 17 -1 (-3175 3575)(-3175 3475);
WIRE 17 -1 (-3175 3600)(-3175 3575);
WIRE 17 -1 (-3175 3475)(-3175 3375);
WIRE 17 -1 (-3175 3375)(-3175 3275);
WIRE 17 -1 (-3175 3600)(-2475 3600);
FORCEPROP 2 LAST SIG_NAME M_A_CPU1_SB_DQS_DP<9:0>
J 2
(-2475 3610);
DISPLAY 0.489362 (-2475 3610);
WIRE 17 -1 (-2975 3425)(-2975 3325);
WIRE 17 -1 (-2975 3525)(-2975 3425);
WIRE 17 -1 (-2975 3325)(-2975 3225);
WIRE 17 -1 (-2975 3225)(-2975 3125);
WIRE 17 -1 (-2975 3550)(-2975 3525);
WIRE 17 -1 (-2975 3550)(-2475 3550);
FORCEPROP 2 LAST SIG_NAME M_A_CPU1_SB_DQS_DN<9:0>
J 2
(-2475 3560);
DISPLAY 0.489362 (-2475 3560);
WIRE 17 -1 (-3175 3275)(-3175 3175);
WIRE 17 -1 (-3175 3075)(-3175 3175);
WIRE 17 -1 (-3175 2975)(-3175 3075);
WIRE 17 -1 (-3175 2875)(-3175 2975);
WIRE 17 -1 (-2975 3775)(-2975 3675);
WIRE 17 -1 (-2975 3875)(-2975 3775);
WIRE 17 -1 (-3175 3825)(-3175 3725);
WIRE 17 -1 (-2975 2725)(-2975 2625);
WIRE 17 -1 (-2975 2825)(-2975 2725);
WIRE 17 -1 (-2975 2825)(-2975 2925);
WIRE 17 -1 (-2975 2925)(-2975 3025);
WIRE 17 -1 (-2975 3025)(-2975 3125);
WIRE 17 -1 (-3175 2775)(-3175 2675);
WIRE 17 -1 (-3175 2875)(-3175 2775);
WIRE 16 -1 (-6125 1125)(-6125 1200);
WIRE 16 -1 (-8600 3150)(-8600 3225);
WIRE 16 -1 (-8525 2475)(-8525 2500);
WIRE 16 -1 (-8275 2475)(-8275 2500);
WIRE 16 -1 (-7600 2775)(-8025 2775);
FORCEPROP 2 LAST SIG_NAME I3C_SPD_DDRAF_CPU1_SCL
J 0
(-8085 2785);
DISPLAY 0.489362 (-8085 2785);
WIRE 16 -1 (-7300 2875)(-7300 2775);
WIRE 16 -1 (-7200 2875)(-7300 2875);
FORCEPROP 2 LAST SIG_NAME I3C_SPD_DDRA_CPU1_SCL
J 0
(-7685 2885);
DISPLAY 0.446809 (-7685 2885);
FORCEPROP 2 LASTPROP $XRERR UNIQUE?
J 0
(-7925 2885);
DISPLAY 0.638298 (-7925 2885);
PAINT MONO (-7925 2885);
DISPLAY INVISIBLE (-7925 2885);
WIRE 16 -1 (-7300 2775)(-7400 2775);
WIRE 16 -1 (-8275 2275)(-8275 2225);
WIRE 16 -1 (-8075 2225)(-8275 2225);
WIRE 16 -1 (-8275 2225)(-8300 2225);
WIRE 16 -1 (-8075 2225)(-8075 2625);
WIRE 16 -1 (-7200 2625)(-8075 2625);
FORCEPROP 2 LAST SIG_NAME PWRGD_CHA_CPU1_DIMM0
J 0
(-7850 2635);
DISPLAY 0.489362 (-7850 2635);
FORCEPROP 2 LASTPROP $XRERR UNIQUE?
J 0
(-8090 2635);
DISPLAY 0.638298 (-8090 2635);
PAINT MONO (-8090 2635);
DISPLAY INVISIBLE (-8090 2635);
WIRE 16 -1 (-7200 2525)(-7850 2525);
FORCEPROP 2 LAST SIG_NAME TP_CHA_CPU1_DIMM0_RFU_6
J 0
(-7850 2535);
DISPLAY 0.489362 (-7850 2535);
FORCEPROP 2 LASTPROP $XRERR UNIQUE?
J 0
(-8090 2525);
DISPLAY 0.638298 (-8090 2525);
PAINT MONO (-8090 2525);
DISPLAY INVISIBLE (-8090 2525);
WIRE 16 -1 (-7200 2925)(-8000 2925);
FORCEPROP 2 LAST SIG_NAME I3C_SPD_DDRAF_CPU1_SDA
J 0
(-8010 2935);
DISPLAY 0.489362 (-8010 2935);
WIRE 16 -1 (-8500 3025)(-7200 3025);
WIRE 16 -1 (-8500 3450)(-8500 3025);
WIRE 16 -1 (-8500 3500)(-8500 3450);
WIRE 16 -1 (-8600 3450)(-8500 3450);
WIRE 16 -1 (-8600 3425)(-8600 3450);
WIRE 16 -1 (-7200 2975)(-8000 2975);
FORCEPROP 2 LAST SIG_NAME PD_CHA_CPU1_DIMM0_SAA
J 0
(-8000 2985);
DISPLAY 0.489362 (-8000 2985);
WIRE 16 -1 (-7200 3125)(-8000 3125);
FORCEPROP 2 LAST SIG_NAME M_A_CPU1_ALERT_N
J 0
(-7985 3135);
DISPLAY 0.489362 (-7985 3135);
WIRE 16 -1 (-7200 3175)(-8000 3175);
FORCEPROP 2 LAST SIG_NAME M_A_CPU1_RESET_N
J 0
(-7985 3185);
DISPLAY 0.489362 (-7985 3185);
WIRE 16 -1 (-7200 2225)(-7850 2225);
FORCEPROP 2 LAST SIG_NAME TP_CHA_CPU1_DIMM0_RFU_0
J 0
(-7850 2235);
DISPLAY 0.489362 (-7850 2235);
FORCEPROP 2 LASTPROP $XRERR UNIQUE?
J 0
(-8090 2225);
DISPLAY 0.638298 (-8090 2225);
PAINT MONO (-8090 2225);
DISPLAY INVISIBLE (-8090 2225);
WIRE 16 -1 (-7200 2275)(-7850 2275);
FORCEPROP 2 LAST SIG_NAME TP_CHA_CPU1_DIMM0_RFU_1
J 0
(-7850 2285);
DISPLAY 0.489362 (-7850 2285);
FORCEPROP 2 LASTPROP $XRERR UNIQUE?
J 0
(-8090 2275);
DISPLAY 0.638298 (-8090 2275);
PAINT MONO (-8090 2275);
DISPLAY INVISIBLE (-8090 2275);
WIRE 16 -1 (-7200 2325)(-7850 2325);
FORCEPROP 2 LAST SIG_NAME TP_CHA_CPU1_DIMM0_RFU_2
J 0
(-7850 2335);
DISPLAY 0.489362 (-7850 2335);
FORCEPROP 2 LASTPROP $XRERR UNIQUE?
J 0
(-8090 2325);
DISPLAY 0.638298 (-8090 2325);
PAINT MONO (-8090 2325);
DISPLAY INVISIBLE (-8090 2325);
WIRE 16 -1 (-7200 2375)(-7850 2375);
FORCEPROP 2 LAST SIG_NAME TP_CHA_CPU1_DIMM0_RFU_3
J 0
(-7850 2385);
DISPLAY 0.489362 (-7850 2385);
FORCEPROP 2 LASTPROP $XRERR UNIQUE?
J 0
(-8090 2375);
DISPLAY 0.638298 (-8090 2375);
PAINT MONO (-8090 2375);
DISPLAY INVISIBLE (-8090 2375);
WIRE 16 -1 (-7200 2425)(-7850 2425);
FORCEPROP 2 LAST SIG_NAME TP_CHA_CPU1_DIMM0_RFU_4
J 0
(-7850 2435);
DISPLAY 0.489362 (-7850 2435);
FORCEPROP 2 LASTPROP $XRERR UNIQUE?
J 0
(-8090 2425);
DISPLAY 0.638298 (-8090 2425);
PAINT MONO (-8090 2425);
DISPLAY INVISIBLE (-8090 2425);
WIRE 16 -1 (-7200 5475)(-7400 5475);
WIRE 16 -1 (-7200 5325)(-7400 5325);
WIRE 16 -1 (-7200 5225)(-7400 5225);
WIRE 16 -1 (-500 5475)(-500 5425);
WIRE 16 -1 (-500 5475)(-700 5475);
WIRE 16 -1 (-500 5425)(-500 5375);
WIRE 16 -1 (-500 5425)(-700 5425);
WIRE 16 -1 (-500 5375)(-500 5325);
WIRE 16 -1 (-500 5375)(-700 5375);
WIRE 16 -1 (-500 5325)(-500 5275);
WIRE 16 -1 (-500 5325)(-700 5325);
WIRE 16 -1 (-500 5275)(-500 5225);
WIRE 16 -1 (-500 5275)(-700 5275);
WIRE 16 -1 (-500 5225)(-500 5175);
WIRE 16 -1 (-500 5225)(-700 5225);
WIRE 16 -1 (-500 5175)(-500 5125);
WIRE 16 -1 (-500 5175)(-700 5175);
WIRE 16 -1 (-500 5125)(-700 5125);
WIRE 16 -1 (-500 5125)(-500 5075);
WIRE 16 -1 (-500 5075)(-500 5025);
WIRE 16 -1 (-500 5075)(-700 5075);
WIRE 16 -1 (-500 5025)(-500 4975);
WIRE 16 -1 (-500 5025)(-700 5025);
WIRE 16 -1 (-500 4975)(-500 4925);
WIRE 16 -1 (-500 4975)(-700 4975);
WIRE 16 -1 (-500 4925)(-500 4875);
WIRE 16 -1 (-500 4925)(-700 4925);
WIRE 16 -1 (-500 4875)(-500 4825);
WIRE 16 -1 (-500 4875)(-700 4875);
WIRE 16 -1 (-500 4825)(-500 4775);
WIRE 16 -1 (-500 4825)(-700 4825);
WIRE 16 -1 (-500 4775)(-500 4725);
WIRE 16 -1 (-500 4775)(-700 4775);
WIRE 16 -1 (-500 4725)(-500 4675);
WIRE 16 -1 (-500 4725)(-700 4725);
WIRE 16 -1 (-500 4675)(-500 4625);
WIRE 16 -1 (-500 4675)(-700 4675);
WIRE 16 -1 (-500 4625)(-500 4575);
WIRE 16 -1 (-500 4625)(-700 4625);
WIRE 16 -1 (-500 4575)(-500 4525);
WIRE 16 -1 (-500 4575)(-700 4575);
WIRE 16 -1 (-500 4525)(-500 4475);
WIRE 16 -1 (-500 4525)(-700 4525);
WIRE 16 -1 (-500 4475)(-500 4425);
WIRE 16 -1 (-500 4475)(-700 4475);
WIRE 16 -1 (-500 4425)(-500 4375);
WIRE 16 -1 (-500 4425)(-700 4425);
WIRE 16 -1 (-500 4375)(-500 4325);
WIRE 16 -1 (-500 4375)(-700 4375);
WIRE 16 -1 (-500 4325)(-500 4275);
WIRE 16 -1 (-500 4325)(-700 4325);
WIRE 16 -1 (-500 4275)(-500 4225);
WIRE 16 -1 (-500 4275)(-700 4275);
WIRE 16 -1 (-500 4225)(-500 4175);
WIRE 16 -1 (-500 4225)(-700 4225);
WIRE 16 -1 (-500 4175)(-500 4125);
WIRE 16 -1 (-500 4175)(-700 4175);
WIRE 16 -1 (-500 4125)(-700 4125);
WIRE 16 -1 (-500 4125)(-500 4075);
WIRE 16 -1 (-500 4075)(-500 4025);
WIRE 16 -1 (-500 4075)(-700 4075);
WIRE 16 -1 (-500 4025)(-500 3975);
WIRE 16 -1 (-500 4025)(-700 4025);
WIRE 16 -1 (-500 3975)(-500 3925);
WIRE 16 -1 (-500 3975)(-700 3975);
WIRE 16 -1 (-500 3925)(-500 3875);
WIRE 16 -1 (-500 3925)(-700 3925);
WIRE 16 -1 (-500 3875)(-500 3825);
WIRE 16 -1 (-500 3875)(-700 3875);
WIRE 16 -1 (-500 3825)(-500 3775);
WIRE 16 -1 (-500 3825)(-700 3825);
WIRE 16 -1 (-500 3775)(-500 3725);
WIRE 16 -1 (-500 3775)(-700 3775);
WIRE 16 -1 (-500 3725)(-500 3675);
WIRE 16 -1 (-500 3725)(-700 3725);
WIRE 16 -1 (-500 3675)(-500 3625);
WIRE 16 -1 (-500 3675)(-700 3675);
WIRE 16 -1 (-500 3625)(-500 3575);
WIRE 16 -1 (-500 3625)(-700 3625);
WIRE 16 -1 (-500 3575)(-500 3525);
WIRE 16 -1 (-500 3575)(-700 3575);
WIRE 16 -1 (-500 3525)(-500 3475);
WIRE 16 -1 (-500 3525)(-700 3525);
WIRE 16 -1 (-500 3475)(-500 3425);
WIRE 16 -1 (-500 3475)(-700 3475);
WIRE 16 -1 (-500 3425)(-500 3375);
WIRE 16 -1 (-500 3425)(-700 3425);
WIRE 16 -1 (-500 3375)(-500 3325);
WIRE 16 -1 (-500 3375)(-700 3375);
WIRE 16 -1 (-500 3325)(-500 3275);
WIRE 16 -1 (-500 3325)(-700 3325);
WIRE 16 -1 (-500 3275)(-500 3225);
WIRE 16 -1 (-500 3275)(-700 3275);
WIRE 16 -1 (-500 3225)(-500 3175);
WIRE 16 -1 (-500 3225)(-700 3225);
WIRE 16 -1 (-500 3175)(-500 3125);
WIRE 16 -1 (-500 3175)(-700 3175);
WIRE 16 -1 (-500 3125)(-500 3075);
WIRE 16 -1 (-500 3125)(-700 3125);
WIRE 16 -1 (-500 3075)(-700 3075);
WIRE 16 -1 (-500 3075)(-500 3025);
WIRE 16 -1 (-500 3025)(-500 2975);
WIRE 16 -1 (-500 3025)(-700 3025);
WIRE 16 -1 (-500 2975)(-500 2925);
WIRE 16 -1 (-500 2975)(-700 2975);
WIRE 16 -1 (-500 2925)(-500 2875);
WIRE 16 -1 (-500 2925)(-700 2925);
WIRE 16 -1 (-500 2875)(-500 2825);
WIRE 16 -1 (-500 2875)(-700 2875);
WIRE 16 -1 (-500 2825)(-500 2775);
WIRE 16 -1 (-500 2825)(-700 2825);
WIRE 16 -1 (-500 2775)(-500 2725);
WIRE 16 -1 (-500 2775)(-700 2775);
WIRE 16 -1 (-500 2725)(-500 2675);
WIRE 16 -1 (-500 2725)(-700 2725);
WIRE 16 -1 (-500 2675)(-500 2625);
WIRE 16 -1 (-500 2675)(-700 2675);
WIRE 16 -1 (-500 2625)(-500 2575);
WIRE 16 -1 (-500 2625)(-700 2625);
WIRE 16 -1 (-500 2575)(-500 2525);
WIRE 16 -1 (-500 2575)(-700 2575);
WIRE 16 -1 (-500 2525)(-500 2475);
WIRE 16 -1 (-500 2525)(-700 2525);
WIRE 16 -1 (-500 2475)(-500 2425);
WIRE 16 -1 (-500 2475)(-700 2475);
WIRE 16 -1 (-500 2425)(-500 2375);
WIRE 16 -1 (-500 2425)(-700 2425);
WIRE 16 -1 (-500 2375)(-500 2325);
WIRE 16 -1 (-500 2375)(-700 2375);
WIRE 16 -1 (-500 2325)(-500 2225);
WIRE 16 -1 (-500 2325)(-700 2325);
WIRE 16 -1 (-500 2225)(-500 2175);
WIRE 16 -1 (-500 2225)(-700 2225);
WIRE 16 -1 (-500 2175)(-500 2125);
WIRE 16 -1 (-500 2175)(-700 2175);
WIRE 16 -1 (-500 2125)(-700 2125);
WIRE 16 -1 (-500 2125)(-500 1925);
WIRE 16 -1 (-1900 5375)(-2100 5375);
WIRE 16 -1 (-2100 5375)(-2100 5425);
WIRE 16 -1 (-1900 5425)(-2100 5425);
WIRE 16 -1 (-2100 5425)(-2100 5475);
WIRE 16 -1 (-1900 5475)(-2100 5475);
WIRE 16 -1 (-2100 5475)(-2100 6300);
WIRE 16 -1 (-2225 6300)(-2100 6300);
WIRE 16 -1 (-2225 6300)(-2800 6300);
WIRE 16 -1 (-2225 6300)(-2225 6200);
WIRE 16 -1 (-2800 6300)(-2800 6375);
WIRE 16 -1 (-2800 6200)(-2800 6300);
WIRE 16 -1 (-1900 5325)(-2100 5325);
WIRE 16 -1 (-2100 5325)(-2100 5275);
WIRE 16 -1 (-1900 5275)(-2100 5275);
WIRE 16 -1 (-2100 5275)(-2100 5225);
WIRE 16 -1 (-1900 5225)(-2100 5225);
WIRE 16 -1 (-2100 5225)(-2100 5175);
WIRE 16 -1 (-1900 5175)(-2100 5175);
WIRE 16 -1 (-2100 5175)(-2100 5125);
WIRE 16 -1 (-1900 5125)(-2100 5125);
WIRE 16 -1 (-2100 5125)(-2100 5075);
WIRE 16 -1 (-1900 5075)(-2100 5075);
WIRE 16 -1 (-2100 5075)(-2100 5025);
WIRE 16 -1 (-1900 5025)(-2100 5025);
WIRE 16 -1 (-2100 5025)(-2100 4975);
WIRE 16 -1 (-1900 4975)(-2100 4975);
WIRE 16 -1 (-2100 4975)(-2100 4925);
WIRE 16 -1 (-1900 4925)(-2100 4925);
WIRE 16 -1 (-2100 4925)(-2100 4875);
WIRE 16 -1 (-1900 4875)(-2100 4875);
WIRE 16 -1 (-2100 4875)(-2100 4825);
WIRE 16 -1 (-1900 4825)(-2100 4825);
WIRE 16 -1 (-2100 4825)(-2100 4775);
WIRE 16 -1 (-1900 4775)(-2100 4775);
WIRE 16 -1 (-2100 4775)(-2100 4725);
WIRE 16 -1 (-1900 4725)(-2100 4725);
WIRE 16 -1 (-2100 4725)(-2100 4675);
WIRE 16 -1 (-1900 4675)(-2100 4675);
WIRE 16 -1 (-2100 4675)(-2100 4625);
WIRE 16 -1 (-1900 4625)(-2100 4625);
WIRE 16 -1 (-2100 4625)(-2100 4575);
WIRE 16 -1 (-1900 4575)(-2100 4575);
WIRE 16 -1 (-2100 4575)(-2100 4525);
WIRE 16 -1 (-1900 4525)(-2100 4525);
WIRE 16 -1 (-2100 4525)(-2100 4475);
WIRE 16 -1 (-1900 4475)(-2100 4475);
WIRE 16 -1 (-2100 4475)(-2100 4425);
WIRE 16 -1 (-1900 4425)(-2100 4425);
WIRE 16 -1 (-2100 4425)(-2100 4375);
WIRE 16 -1 (-1900 4375)(-2100 4375);
WIRE 16 -1 (-2100 4375)(-2100 4325);
WIRE 16 -1 (-1900 4325)(-2100 4325);
WIRE 16 -1 (-2100 4325)(-2100 4275);
WIRE 16 -1 (-1900 4275)(-2100 4275);
WIRE 16 -1 (-2100 4275)(-2100 4225);
WIRE 16 -1 (-1900 4225)(-2100 4225);
WIRE 16 -1 (-2100 4225)(-2100 4175);
WIRE 16 -1 (-1900 4175)(-2100 4175);
WIRE 16 -1 (-2100 4175)(-2100 4125);
WIRE 16 -1 (-1900 4125)(-2100 4125);
WIRE 16 -1 (-2100 4125)(-2100 4075);
WIRE 16 -1 (-1900 4075)(-2100 4075);
WIRE 16 -1 (-2100 4075)(-2100 4025);
WIRE 16 -1 (-1900 4025)(-2100 4025);
WIRE 16 -1 (-2100 4025)(-2100 3975);
WIRE 16 -1 (-1900 3975)(-2100 3975);
WIRE 16 -1 (-2100 3975)(-2100 3925);
WIRE 16 -1 (-1900 3925)(-2100 3925);
WIRE 16 -1 (-2100 3925)(-2100 3875);
WIRE 16 -1 (-1900 3875)(-2100 3875);
WIRE 16 -1 (-2100 3875)(-2100 3825);
WIRE 16 -1 (-1900 3825)(-2100 3825);
WIRE 16 -1 (-2100 3825)(-2100 3775);
WIRE 16 -1 (-1900 3775)(-2100 3775);
WIRE 16 -1 (-2100 3775)(-2100 3725);
WIRE 16 -1 (-1900 3725)(-2100 3725);
WIRE 16 -1 (-2100 3725)(-2100 3675);
WIRE 16 -1 (-1900 3675)(-2100 3675);
WIRE 16 -1 (-2100 3675)(-2100 3625);
WIRE 16 -1 (-1900 3625)(-2100 3625);
WIRE 16 -1 (-2100 3625)(-2100 3575);
WIRE 16 -1 (-1900 3575)(-2100 3575);
WIRE 16 -1 (-2100 3575)(-2100 3525);
WIRE 16 -1 (-1900 3525)(-2100 3525);
WIRE 16 -1 (-2100 3525)(-2100 3475);
WIRE 16 -1 (-1900 3475)(-2100 3475);
WIRE 16 -1 (-2100 3475)(-2100 3425);
WIRE 16 -1 (-1900 3425)(-2100 3425);
WIRE 16 -1 (-2100 3425)(-2100 3375);
WIRE 16 -1 (-1900 3375)(-2100 3375);
WIRE 16 -1 (-2100 3375)(-2100 3325);
WIRE 16 -1 (-1900 3325)(-2100 3325);
WIRE 16 -1 (-2100 3325)(-2100 3275);
WIRE 16 -1 (-1900 3275)(-2100 3275);
WIRE 16 -1 (-2100 3275)(-2100 3225);
WIRE 16 -1 (-1900 3225)(-2100 3225);
WIRE 16 -1 (-2100 3225)(-2100 3175);
WIRE 16 -1 (-1900 3175)(-2100 3175);
WIRE 16 -1 (-2100 3175)(-2100 3125);
WIRE 16 -1 (-1900 3125)(-2100 3125);
WIRE 16 -1 (-2100 3125)(-2100 3075);
WIRE 16 -1 (-1900 3075)(-2100 3075);
WIRE 16 -1 (-2100 3075)(-2100 3025);
WIRE 16 -1 (-1900 3025)(-2100 3025);
WIRE 16 -1 (-2100 3025)(-2100 2975);
WIRE 16 -1 (-1900 2975)(-2100 2975);
WIRE 16 -1 (-2100 2975)(-2100 2925);
WIRE 16 -1 (-1900 2925)(-2100 2925);
WIRE 16 -1 (-2100 2925)(-2100 2875);
WIRE 16 -1 (-1900 2875)(-2100 2875);
WIRE 16 -1 (-2100 2875)(-2100 2825);
WIRE 16 -1 (-1900 2825)(-2100 2825);
WIRE 16 -1 (-2100 2825)(-2100 2775);
WIRE 16 -1 (-1900 2775)(-2100 2775);
WIRE 16 -1 (-2100 2775)(-2100 2725);
WIRE 16 -1 (-1900 2725)(-2100 2725);
WIRE 16 -1 (-2100 2725)(-2100 2675);
WIRE 16 -1 (-1900 2675)(-2100 2675);
WIRE 16 -1 (-2100 2675)(-2100 2625);
WIRE 16 -1 (-1900 2625)(-2100 2625);
WIRE 16 -1 (-2100 2625)(-2100 2575);
WIRE 16 -1 (-1900 2575)(-2100 2575);
WIRE 16 -1 (-2100 2575)(-2100 2525);
WIRE 16 -1 (-1900 2525)(-2100 2525);
WIRE 16 -1 (-2100 2525)(-2100 2475);
WIRE 16 -1 (-1900 2475)(-2100 2475);
WIRE 16 -1 (-2100 2475)(-2100 2425);
WIRE 16 -1 (-1900 2425)(-2100 2425);
WIRE 16 -1 (-2100 2425)(-2100 2375);
WIRE 16 -1 (-1900 2375)(-2100 2375);
WIRE 16 -1 (-2100 2375)(-2100 2325);
WIRE 16 -1 (-1900 2325)(-2100 2325);
WIRE 16 -1 (-2100 2325)(-2100 2275);
WIRE 16 -1 (-2100 2275)(-2100 2225);
WIRE 16 -1 (-1900 2275)(-2100 2275);
WIRE 16 -1 (-1900 2225)(-2100 2225);
WIRE 16 -1 (-2100 2225)(-2100 2125);
WIRE 16 -1 (-3475 4600)(-3275 4600);
WIRE 16 -1 (-5800 4975)(-6000 4975);
WIRE 16 -1 (-5800 5025)(-6000 5025);
WIRE 16 -1 (-3475 3550)(-3275 3550);
WIRE 16 -1 (-3475 3500)(-3075 3500);
WIRE 16 -1 (-3475 4550)(-3075 4550);
WIRE 16 -1 (-3275 4500)(-3475 4500);
WIRE 16 -1 (-3475 4450)(-3075 4450);
WIRE 16 -1 (-3475 3300)(-3075 3300);
WIRE 16 -1 (-3275 4400)(-3475 4400);
WIRE 16 -1 (-3275 3250)(-3475 3250);
WIRE 16 -1 (-3475 3200)(-3075 3200);
WIRE 16 -1 (-3475 4250)(-3075 4250);
WIRE 16 -1 (-3475 3150)(-3275 3150);
WIRE 16 -1 (-3475 3100)(-3075 3100);
WIRE 16 -1 (-3475 4200)(-3275 4200);
WIRE 16 -1 (-3475 4150)(-3075 4150);
WIRE 16 -1 (-3275 3050)(-3475 3050);
WIRE 16 -1 (-3475 3000)(-3075 3000);
WIRE 16 -1 (-3275 4100)(-3475 4100);
WIRE 16 -1 (-3075 4050)(-3475 4050);
WIRE 16 -1 (-3275 2950)(-3475 2950);
WIRE 16 -1 (-3475 2900)(-3075 2900);
WIRE 16 -1 (-3275 4000)(-3475 4000);
WIRE 16 -1 (-3475 3950)(-3075 3950);
WIRE 16 -1 (-3275 2850)(-3475 2850);
WIRE 16 -1 (-3475 2800)(-3075 2800);
WIRE 16 -1 (-3275 3900)(-3475 3900);
WIRE 16 -1 (-3475 3850)(-3075 3850);
WIRE 16 -1 (-3475 2750)(-3275 2750);
WIRE 16 -1 (-3475 2700)(-3075 2700);
WIRE 16 -1 (-3475 3800)(-3275 3800);
WIRE 16 -1 (-3475 3750)(-3075 3750);
WIRE 16 -1 (-3275 2650)(-3475 2650);
WIRE 16 -1 (-3475 2600)(-3075 2600);
WIRE 16 -1 (-3275 3700)(-3475 3700);
WIRE 16 -1 (-3475 3650)(-3075 3650);
WIRE 16 -1 (-3275 3350)(-3475 3350);
WIRE 16 -1 (-3475 3400)(-3075 3400);
WIRE 16 -1 (-3275 3450)(-3475 3450);
WIRE 16 -1 (-3275 4300)(-3475 4300);
WIRE 16 -1 (-3475 4350)(-3075 4350);
WIRE 16 -1 (-5800 4775)(-6000 4775);
WIRE 16 -1 (-5800 4825)(-6000 4825);
WIRE 16 -1 (-5800 5125)(-6000 5125);
WIRE 16 -1 (-7200 5175)(-7400 5175);
WIRE 16 -1 (-6000 5275)(-5800 5275);
WIRE 16 -1 (-5800 5325)(-6000 5325);
WIRE 16 -1 (-7200 2475)(-7850 2475);
FORCEPROP 2 LAST SIG_NAME TP_CHA_CPU1_DIMM0_RFU_5
J 0
(-7850 2485);
DISPLAY 0.489362 (-7850 2485);
FORCEPROP 2 LASTPROP $XRERR UNIQUE?
J 0
(-8090 2475);
DISPLAY 0.638298 (-8090 2475);
PAINT MONO (-8090 2475);
DISPLAY INVISIBLE (-8090 2475);
WIRE 16 -1 (-7200 4625)(-8000 4625);
FORCEPROP 2 LAST SIG_NAME M_A_CPU1_SB_PAR
J 0
(-8000 4635);
DISPLAY 0.489362 (-8000 4635);
WIRE 16 -1 (-7200 4675)(-8000 4675);
FORCEPROP 2 LAST SIG_NAME M_A_CPU1_SA_PAR
J 0
(-8000 4685);
DISPLAY 0.489362 (-8000 4685);
WIRE 16 -1 (-7200 2025)(-8000 2025);
FORCEPROP 2 LAST SIG_NAME M_A_CPU1_SB_RSP<0>
J 0
(-8000 2035);
DISPLAY 0.489362 (-8000 2035);
WIRE 16 -1 (-7200 2075)(-8000 2075);
FORCEPROP 2 LAST SIG_NAME M_A_CPU1_SA_RSP<0>
J 0
(-8000 2085);
DISPLAY 0.489362 (-8000 2085);
WIRE 16 -1 (-5800 2275)(-6000 2275);
WIRE 16 -1 (-5800 2325)(-6000 2325);
WIRE 16 -1 (-5800 2375)(-6000 2375);
WIRE 16 -1 (-6000 2425)(-5800 2425);
WIRE 16 -1 (-5800 2475)(-6000 2475);
WIRE 16 -1 (-5800 2525)(-6000 2525);
WIRE 16 -1 (-5800 2575)(-6000 2575);
WIRE 16 -1 (-6000 2625)(-5800 2625);
WIRE 16 -1 (-5800 2675)(-6000 2675);
WIRE 16 -1 (-5800 2725)(-6000 2725);
WIRE 16 -1 (-5800 2775)(-6000 2775);
WIRE 16 -1 (-6000 2825)(-5800 2825);
WIRE 16 -1 (-5800 2875)(-6000 2875);
WIRE 16 -1 (-5800 2925)(-6000 2925);
WIRE 16 -1 (-5800 2975)(-6000 2975);
WIRE 16 -1 (-6000 3025)(-5800 3025);
WIRE 16 -1 (-5800 3075)(-6000 3075);
WIRE 16 -1 (-5800 3125)(-6000 3125);
WIRE 16 -1 (-5800 3175)(-6000 3175);
WIRE 16 -1 (-6000 3225)(-5800 3225);
WIRE 16 -1 (-5800 3275)(-6000 3275);
WIRE 16 -1 (-5800 3325)(-6000 3325);
WIRE 16 -1 (-5800 3375)(-6000 3375);
WIRE 16 -1 (-6000 3425)(-5800 3425);
WIRE 16 -1 (-5800 3475)(-6000 3475);
WIRE 16 -1 (-5800 3525)(-6000 3525);
WIRE 16 -1 (-5800 3575)(-6000 3575);
WIRE 16 -1 (-6000 3625)(-5800 3625);
WIRE 16 -1 (-5800 3675)(-6000 3675);
WIRE 16 -1 (-5800 3725)(-6000 3725);
WIRE 16 -1 (-5800 3775)(-6000 3775);
WIRE 16 -1 (-6000 3825)(-5800 3825);
WIRE 16 -1 (-5800 3925)(-6000 3925);
WIRE 16 -1 (-5800 3975)(-6000 3975);
WIRE 16 -1 (-5800 4025)(-6000 4025);
WIRE 16 -1 (-6000 4075)(-5800 4075);
WIRE 16 -1 (-5800 4125)(-6000 4125);
WIRE 16 -1 (-5800 4175)(-6000 4175);
WIRE 16 -1 (-5800 4225)(-6000 4225);
WIRE 16 -1 (-6000 4275)(-5800 4275);
WIRE 16 -1 (-5800 4325)(-6000 4325);
WIRE 16 -1 (-5800 4375)(-6000 4375);
WIRE 16 -1 (-5800 4425)(-6000 4425);
WIRE 16 -1 (-6000 4475)(-5800 4475);
WIRE 16 -1 (-5800 4525)(-6000 4525);
WIRE 16 -1 (-5800 4575)(-6000 4575);
WIRE 16 -1 (-5800 4625)(-6000 4625);
WIRE 16 -1 (-6000 4675)(-5800 4675);
WIRE 16 -1 (-5800 4725)(-6000 4725);
WIRE 16 -1 (-6000 4875)(-5800 4875);
WIRE 16 -1 (-5800 4925)(-6000 4925);
WIRE 16 -1 (-6000 5075)(-5800 5075);
WIRE 16 -1 (-5800 5175)(-6000 5175);
WIRE 16 -1 (-5800 5225)(-6000 5225);
WIRE 16 -1 (-5800 5375)(-6000 5375);
WIRE 16 -1 (-5800 5425)(-6000 5425);
WIRE 16 -1 (-7200 4375)(-8000 4375);
FORCEPROP 2 LAST SIG_NAME M_A_CPU1_SB_CS_N<1>
J 0
(-8000 4385);
DISPLAY 0.489362 (-8000 4385);
WIRE 16 -1 (-7200 4525)(-8000 4525);
FORCEPROP 2 LAST SIG_NAME M_A_CPU1_SA_CS_N<1>
J 0
(-8000 4535);
DISPLAY 0.489362 (-8000 4535);
WIRE 16 -1 (-7200 4325)(-8000 4325);
FORCEPROP 2 LAST SIG_NAME M_A_CPU1_SB_CS_N<0>
J 0
(-8000 4335);
DISPLAY 0.489362 (-8000 4335);
WIRE 16 -1 (-7200 4475)(-8000 4475);
FORCEPROP 2 LAST SIG_NAME M_A_CPU1_SA_CS_N<0>
J 0
(-8000 4485);
DISPLAY 0.489362 (-8000 4485);
WIRE 16 -1 (-7200 4225)(-8000 4225);
FORCEPROP 2 LAST SIG_NAME M_A_CPU1_CLK_DP<0>
J 0
(-8000 4235);
DISPLAY 0.489362 (-8000 4235);
WIRE 16 -1 (-7200 4175)(-8000 4175);
FORCEPROP 2 LAST SIG_NAME M_A_CPU1_CLK_DN<0>
J 0
(-8000 4185);
DISPLAY 0.489362 (-8000 4185);
WIRE 16 -1 (-7200 3275)(-7400 3275);
WIRE 16 -1 (-7200 3325)(-7400 3325);
WIRE 16 -1 (-7200 3375)(-7400 3375);
WIRE 16 -1 (-7200 3425)(-7400 3425);
WIRE 16 -1 (-7200 3475)(-7400 3475);
WIRE 16 -1 (-7200 3525)(-7400 3525);
WIRE 16 -1 (-7200 3575)(-7400 3575);
WIRE 16 -1 (-7200 3725)(-7400 3725);
WIRE 16 -1 (-7200 3825)(-7400 3825);
WIRE 16 -1 (-7200 3875)(-7400 3875);
WIRE 16 -1 (-7200 3975)(-7400 3975);
WIRE 16 -1 (-7200 4025)(-7400 4025);
WIRE 16 -1 (-7200 5075)(-7400 5075);
WIRE 16 -1 (-7200 5025)(-7400 5025);
WIRE 16 -1 (-7200 5425)(-7400 5425);
WIRE 16 -1 (-7200 4975)(-7400 4975);
WIRE 16 -1 (-7200 5375)(-7400 5375);
WIRE 16 -1 (-7200 4925)(-7400 4925);
WIRE 16 -1 (-7200 4875)(-7400 4875);
WIRE 16 -1 (-7200 5275)(-7400 5275);
WIRE 16 -1 (-7200 4825)(-7400 4825);
WIRE 16 -1 (-7200 4775)(-7400 4775);
WIRE 16 -1 (-7200 3625)(-7400 3625);
WIRE 16 -1 (-7200 3775)(-7400 3775);
WIRE 16 -1 (-7200 3925)(-7400 3925);
WIRE 16 -1 (-7200 4075)(-7400 4075);
WIRE 16 -1 (-6000 5475)(-5800 5475);
WIRE 16 -1 (-8500 2225)(-8525 2225);
WIRE 16 -1 (-8525 2275)(-8525 2225);
WIRE 16 -1 (-8525 2225)(-8900 2225);
FORCEPROP 2 LAST SIG_NAME PWRGD_CHAF_CPU1
J 0
(-8935 2235);
DISPLAY 0.489362 (-8935 2235);
WIRE 16 -1 (-6125 1475)(-6125 1400);
WIRE 16 -1 (-6125 1475)(-6850 1475);
FORCEPROP 2 LAST SIG_NAME PD_CHA_CPU1_DIMM0_SAA
J 0
(-6835 1485);
DISPLAY 0.489362 (-6835 1485);
WIRE 16 -1 (-2225 5875)(-2800 5875);
WIRE 16 -1 (-2225 5875)(-2225 6000);
WIRE 16 -1 (-2800 5875)(-2800 6000);
WIRE 16 -1 (-2800 5875)(-2800 5800);
DOT 1 (-2100 5125);
DOT 1 (-8525 2225);
DOT 1 (-2100 2275);
DOT 1 (-8275 2225);
DOT 1 (-8500 3450);
DOT 1 (-2100 2225);
DOT 1 (-2100 2325);
DOT 1 (-2100 2375);
DOT 1 (-2100 2425);
DOT 1 (-2100 2475);
DOT 1 (-2100 2525);
DOT 1 (-2100 2575);
DOT 1 (-2100 2625);
DOT 1 (-2100 2675);
DOT 1 (-2100 2725);
DOT 1 (-2100 2775);
DOT 1 (-2100 2825);
DOT 1 (-2100 2875);
DOT 1 (-2100 2925);
DOT 1 (-2100 2975);
DOT 1 (-2100 3025);
DOT 1 (-2100 3075);
DOT 1 (-2100 3125);
DOT 1 (-2100 3175);
DOT 1 (-2100 3275);
DOT 1 (-2100 3225);
DOT 1 (-2100 3325);
DOT 1 (-2100 3375);
DOT 1 (-2100 3425);
DOT 1 (-2100 3525);
DOT 1 (-2100 3475);
DOT 1 (-2100 3575);
DOT 1 (-2100 3625);
DOT 1 (-2100 3675);
DOT 1 (-500 2125);
DOT 1 (-500 2175);
DOT 1 (-500 2225);
DOT 1 (-500 2325);
DOT 1 (-500 2375);
DOT 1 (-500 2425);
DOT 1 (-500 2475);
DOT 1 (-500 2525);
DOT 1 (-500 2625);
DOT 1 (-500 2575);
DOT 1 (-500 2675);
DOT 1 (-500 2725);
DOT 1 (-500 2775);
DOT 1 (-500 2825);
DOT 1 (-500 2875);
DOT 1 (-500 2925);
DOT 1 (-500 2975);
DOT 1 (-500 3025);
DOT 1 (-500 3075);
DOT 1 (-500 3125);
DOT 1 (-500 3175);
DOT 1 (-500 3275);
DOT 1 (-500 3225);
DOT 1 (-500 3325);
DOT 1 (-500 3375);
DOT 1 (-500 3425);
DOT 1 (-500 3475);
DOT 1 (-500 3525);
DOT 1 (-500 3575);
DOT 1 (-500 3625);
DOT 1 (-500 3675);
DOT 1 (-2100 3775);
DOT 1 (-2100 3725);
DOT 1 (-2100 3825);
DOT 1 (-2100 3875);
DOT 1 (-2100 3925);
DOT 1 (-2100 3975);
DOT 1 (-2100 4025);
DOT 1 (-2100 4075);
DOT 1 (-2100 4175);
DOT 1 (-2100 4125);
DOT 1 (-2100 4225);
DOT 1 (-2100 4275);
DOT 1 (-2100 4325);
DOT 1 (-2100 4375);
DOT 1 (-2100 4475);
DOT 1 (-2100 4525);
DOT 1 (-2100 4575);
DOT 1 (-2100 4675);
DOT 1 (-2100 4625);
DOT 1 (-2100 4725);
DOT 1 (-2100 4775);
DOT 1 (-2100 4825);
DOT 1 (-2100 4875);
DOT 1 (-2100 4925);
DOT 1 (-2100 4975);
DOT 1 (-2100 5075);
DOT 1 (-2100 5025);
DOT 1 (-2100 5175);
DOT 1 (-2100 5225);
DOT 1 (-2100 5275);
DOT 1 (-2100 5475);
DOT 1 (-2100 5425);
DOT 1 (-500 3725);
DOT 1 (-500 3775);
DOT 1 (-500 3825);
DOT 1 (-500 3875);
DOT 1 (-500 3925);
DOT 1 (-500 3975);
DOT 1 (-500 4025);
DOT 1 (-500 4075);
DOT 1 (-500 4125);
DOT 1 (-500 4175);
DOT 1 (-500 4225);
DOT 1 (-500 4275);
DOT 1 (-500 4325);
DOT 1 (-500 4375);
DOT 1 (-500 4425);
DOT 1 (-500 4475);
DOT 1 (-500 4525);
DOT 1 (-500 4575);
DOT 1 (-500 4675);
DOT 1 (-500 4625);
DOT 1 (-500 4725);
DOT 1 (-500 4775);
DOT 1 (-500 4825);
DOT 1 (-500 4875);
DOT 1 (-500 4925);
DOT 1 (-500 4975);
DOT 1 (-500 5025);
DOT 1 (-500 5075);
DOT 1 (-500 5125);
DOT 1 (-500 5175);
DOT 1 (-500 5225);
DOT 1 (-500 5325);
DOT 1 (-500 5275);
DOT 1 (-500 5375);
DOT 1 (-500 5425);
DOT 1 (-2800 5875);
DOT 1 (-2800 6300);
DOT 1 (-2225 6300);
DOT 1 (-2100 4425);
QUIT
